FILE_TYPE = MACRO_DRAWING;
SET COLOR_WIRE YELLOW;
SET COLOR_PROP ORANGE;
SET COLOR_DOT WHITE;
SET COLOR_ARC YELLOW;
SET COLOR_BODY GREEN;
SET COLOR_NOTE PURPLE;
SET PROP_DISPLAY VALUE;
SET PAGE_NUMBER P143;
FORCEADD UNIVERSAL_POWER..1
(-1875 5725);
FORCEPROP 3 LASTPIN (-1875 5675) SIG_NAME P3V3_AUX\g
J 0
(-1865 5685);
DISPLAY 0.659574 (-1865 5685);
PAINT MONO (-1865 5685);
DISPLAY INVISIBLE (-1865 5685);
FORCEPROP 1 LAST HDL_POWER P3V3_AUX
J 1
(-1875 5775);
DISPLAY 0.489362 (-1875 5775);
PAINT GREEN (-1875 5775);
FORCEPROP 2 LAST BOM_COST OCP3.0 
J 0
(-1875 5825);
DISPLAY 0.680851 (-1875 5825);
DISPLAY INVISIBLE (-1875 5825);
FORCEPROP 2 LAST CDS_LIB pure_quanta_power
J 0
(-1875 5725);
DISPLAY INVISIBLE (-1875 5725);
FORCEPROP 1 LAST PATH I1
J 0
(-1825 5750);
DISPLAY 0.872340 (-1825 5750);
PAINT AQUA (-1825 5750);
DISPLAY INVISIBLE (-1825 5750);
FORCEADD UNIVERSAL_POWER..1
(-4100 4150);
FORCEPROP 3 LASTPIN (-4100 4100) SIG_NAME P3V3_AUX\g
J 0
(-4090 4110);
DISPLAY 0.659574 (-4090 4110);
PAINT MONO (-4090 4110);
DISPLAY INVISIBLE (-4090 4110);
FORCEPROP 1 LAST HDL_POWER P3V3_AUX
J 1
(-4100 4200);
DISPLAY 0.489362 (-4100 4200);
PAINT GREEN (-4100 4200);
FORCEPROP 2 LAST BOM_COST OCP3.0 
J 0
(-4100 4250);
DISPLAY 0.680851 (-4100 4250);
DISPLAY INVISIBLE (-4100 4250);
FORCEPROP 2 LAST CDS_LIB pure_quanta_power
J 0
(-4100 4150);
DISPLAY INVISIBLE (-4100 4150);
FORCEPROP 1 LAST PATH I10
J 0
(-4050 4175);
DISPLAY 0.872340 (-4050 4175);
PAINT AQUA (-4050 4175);
DISPLAY INVISIBLE (-4050 4175);
FORCEADD Q_RES..2
(-4100 3800);
FORCEPROP 1 LAST LOCATION R947
J 0
(-4055 3925);
DISPLAY 0.489362 (-4055 3925);
PAINT SKYBLUE (-4055 3925);
FORCEPROP 0 LAST $SEC 1
J 0
(-4050 3975);
DISPLAY 0.680851 (-4050 3975);
PAINT MONO (-4050 3975);
DISPLAY INVISIBLE (-4050 3975);
FORCEPROP 0 LAST CDS_SEC 1
J 0
(-4050 3975);
DISPLAY 0.680851 (-4050 3975);
DISPLAY INVISIBLE (-4050 3975);
FORCEPROP 1 LASTPIN (-4100 3900) $PN 1
J 0
(-4095 3862);
DISPLAY 0.489362 (-4095 3862);
PAINT MONO (-4095 3862);
FORCEPROP 1 LASTPIN (-4100 3700) $PN 2
J 0
(-4095 3710);
DISPLAY 0.489362 (-4095 3710);
PAINT MONO (-4095 3710);
FORCEPROP 1 LAST VALUE 4.7K
J 0
(-4055 3875);
DISPLAY 0.489362 (-4055 3875);
PAINT SKYBLUE (-4055 3875);
FORCEPROP 1 LAST MATERIAL CHIP
J 0
(-4060 3725);
DISPLAY 0.489362 (-4060 3725);
PAINT SKYBLUE (-4060 3725);
FORCEPROP 1 LAST TOLERANCE 5%
J 0
(-4055 3825);
DISPLAY 0.489362 (-4055 3825);
PAINT SKYBLUE (-4055 3825);
FORCEPROP 1 LAST WATTAGE 1/16W
J 0
(-4060 3775);
DISPLAY 0.489362 (-4060 3775);
PAINT SKYBLUE (-4060 3775);
FORCEPROP 1 LAST PACK_TYPE 0402LF
J 0
(-4060 3625);
DISPLAY 0.489362 (-4060 3625);
PAINT SKYBLUE (-4060 3625);
DISPLAY INVISIBLE (-4060 3625);
FORCEPROP 2 LAST BOM_COST OCP3.0 
J 0
(-4050 3975);
DISPLAY 0.680851 (-4050 3975);
DISPLAY INVISIBLE (-4050 3975);
FORCEPROP 2 LAST CDS_LIB pure_quanta
J 0
(-4100 3800);
DISPLAY INVISIBLE (-4100 3800);
FORCEPROP 1 LAST PATH I11
J 0
(-4050 3975);
DISPLAY 0.978723 (-4050 3975);
PAINT WHITE (-4050 3975);
DISPLAY INVISIBLE (-4050 3975);
FORCEPROP 1 LAST PART_NUMBER CS24702JB10
J 0
(-4060 3675);
DISPLAY 0.489362 (-4060 3675);
PAINT SKYBLUE (-4060 3675);
DISPLAY INVISIBLE (-4060 3675);
FORCEADD GND..1
R 1
(-4150 3550);
FORCEPROP 3 LASTPIN (-4200 3550) SIG_NAME GND\g
J 0
(-4190 3560);
DISPLAY 0.659574 (-4190 3560);
PAINT MONO (-4190 3560);
DISPLAY INVISIBLE (-4190 3560);
FORCEPROP 1 LAST SIZE 1B
R 1
J 0
(-4100 3625);
DISPLAY 0.851064 (-4100 3625);
PAINT GREEN (-4100 3625);
DISPLAY INVISIBLE (-4100 3625);
FORCEPROP 2 LAST BOM_COST MEM
R 1
J 0
(-4225 3450);
DISPLAY 0.808511 (-4225 3450);
DISPLAY INVISIBLE (-4225 3450);
FORCEPROP 2 LAST CDS_LIB pure_quanta_power
J 0
(-4150 3550);
DISPLAY INVISIBLE (-4150 3550);
FORCEPROP 1 LAST HDL_POWER GND
R 1
J 0
(-4300 3550);
DISPLAY 0.851064 (-4300 3550);
PAINT GREEN (-4300 3550);
DISPLAY INVISIBLE (-4300 3550);
FORCEPROP 1 LAST PATH I12
R 1
J 0
(-4150 3625);
DISPLAY 0.872340 (-4150 3625);
PAINT AQUA (-4150 3625);
DISPLAY INVISIBLE (-4150 3625);
FORCEADD GND..1
R 5
(-4775 5175);
FORCEPROP 3 LASTPIN (-4725 5175) SIG_NAME GND\g
J 0
(-4715 5185);
DISPLAY 0.659574 (-4715 5185);
PAINT MONO (-4715 5185);
DISPLAY INVISIBLE (-4715 5185);
FORCEPROP 2 LAST BOM_COST MEM
R 3
J 0
(-4700 5275);
DISPLAY 0.808511 (-4700 5275);
DISPLAY INVISIBLE (-4700 5275);
FORCEPROP 1 LAST SIZE 1B
R 3
J 0
(-4825 5100);
DISPLAY 0.851064 (-4825 5100);
PAINT GREEN (-4825 5100);
DISPLAY INVISIBLE (-4825 5100);
FORCEPROP 2 LAST CDS_LIB pure_quanta_power
J 0
(-4775 5175);
DISPLAY INVISIBLE (-4775 5175);
FORCEPROP 1 LAST HDL_POWER GND
R 3
J 0
(-4625 5175);
DISPLAY 0.851064 (-4625 5175);
PAINT GREEN (-4625 5175);
DISPLAY INVISIBLE (-4625 5175);
FORCEPROP 1 LAST PATH I13
R 3
J 0
(-4775 5100);
DISPLAY 0.872340 (-4775 5100);
PAINT AQUA (-4775 5100);
DISPLAY INVISIBLE (-4775 5100);
FORCEADD UNIVERSAL_POWER..1
(-4950 5775);
FORCEPROP 3 LASTPIN (-4950 5725) SIG_NAME P3V3_AUX\g
J 0
(-4940 5735);
DISPLAY 0.659574 (-4940 5735);
PAINT MONO (-4940 5735);
DISPLAY INVISIBLE (-4940 5735);
FORCEPROP 1 LAST HDL_POWER P3V3_AUX
J 1
(-4950 5825);
DISPLAY 0.489362 (-4950 5825);
PAINT GREEN (-4950 5825);
FORCEPROP 2 LAST BOM_COST OCP3.0 
J 0
(-4950 5875);
DISPLAY 0.680851 (-4950 5875);
DISPLAY INVISIBLE (-4950 5875);
FORCEPROP 2 LAST CDS_LIB pure_quanta_power
J 0
(-4950 5775);
DISPLAY INVISIBLE (-4950 5775);
FORCEPROP 1 LAST PATH I14
J 0
(-4900 5800);
DISPLAY 0.872340 (-4900 5800);
PAINT AQUA (-4900 5800);
DISPLAY INVISIBLE (-4900 5800);
FORCEADD Q_RES..2
(-4950 5425);
FORCEPROP 1 LAST LOCATION R944
J 0
(-4905 5550);
DISPLAY 0.489362 (-4905 5550);
PAINT SKYBLUE (-4905 5550);
FORCEPROP 0 LAST $SEC 1
J 0
(-4900 5600);
DISPLAY 0.680851 (-4900 5600);
PAINT MONO (-4900 5600);
DISPLAY INVISIBLE (-4900 5600);
FORCEPROP 0 LAST CDS_SEC 1
J 0
(-4900 5600);
DISPLAY 0.680851 (-4900 5600);
DISPLAY INVISIBLE (-4900 5600);
FORCEPROP 1 LASTPIN (-4950 5525) $PN 1
J 0
(-4945 5487);
DISPLAY 0.489362 (-4945 5487);
PAINT MONO (-4945 5487);
FORCEPROP 1 LASTPIN (-4950 5325) $PN 2
J 0
(-4945 5335);
DISPLAY 0.489362 (-4945 5335);
PAINT MONO (-4945 5335);
FORCEPROP 1 LAST TOLERANCE 5%
J 0
(-4905 5450);
DISPLAY 0.489362 (-4905 5450);
PAINT SKYBLUE (-4905 5450);
FORCEPROP 1 LAST MATERIAL CHIP
J 0
(-4910 5350);
DISPLAY 0.489362 (-4910 5350);
PAINT SKYBLUE (-4910 5350);
FORCEPROP 1 LAST WATTAGE 1/16W
J 0
(-4910 5400);
DISPLAY 0.489362 (-4910 5400);
PAINT SKYBLUE (-4910 5400);
FORCEPROP 1 LAST VALUE 4.7K
J 0
(-4905 5500);
DISPLAY 0.489362 (-4905 5500);
PAINT SKYBLUE (-4905 5500);
FORCEPROP 1 LAST PACK_TYPE 0402LF
J 0
(-4910 5250);
DISPLAY 0.489362 (-4910 5250);
PAINT SKYBLUE (-4910 5250);
DISPLAY INVISIBLE (-4910 5250);
FORCEPROP 2 LAST BOM_COST OCP3.0 
J 0
(-4900 5600);
DISPLAY 0.680851 (-4900 5600);
DISPLAY INVISIBLE (-4900 5600);
FORCEPROP 2 LAST CDS_LIB pure_quanta
J 0
(-4950 5425);
DISPLAY INVISIBLE (-4950 5425);
FORCEPROP 1 LAST PATH I15
J 0
(-4900 5600);
DISPLAY 0.978723 (-4900 5600);
PAINT WHITE (-4900 5600);
DISPLAY INVISIBLE (-4900 5600);
FORCEPROP 1 LAST PART_NUMBER CS24702JB10
J 0
(-4910 5300);
DISPLAY 0.489362 (-4910 5300);
PAINT SKYBLUE (-4910 5300);
DISPLAY INVISIBLE (-4910 5300);
FORCEADD MOSFET_DUAL_6P..1
(-4400 5125);
FORCEPROP 1 LAST LOCATION Q2
J 0
(-4547 5334);
DISPLAY 0.489362 (-4547 5334);
PAINT SKYBLUE (-4547 5334);
FORCEPROP 0 LAST $SEC 1
J 0
(-4525 5475);
DISPLAY 0.680851 (-4525 5475);
PAINT MONO (-4525 5475);
DISPLAY INVISIBLE (-4525 5475);
FORCEPROP 0 LAST CDS_SEC 1
J 0
(-4525 5475);
DISPLAY 0.680851 (-4525 5475);
DISPLAY INVISIBLE (-4525 5475);
FORCEPROP 0 LASTPIN (-4700 5075) $PN 6
J 2
(-4710 5085);
DISPLAY 0.489362 (-4710 5085);
PAINT MONO (-4710 5085);
FORCEPROP 0 LASTPIN (-4100 5075) $PN 3
J 0
(-4090 5085);
DISPLAY 0.489362 (-4090 5085);
PAINT MONO (-4090 5085);
FORCEPROP 0 LASTPIN (-4700 5125) $PN 2
J 2
(-4710 5135);
DISPLAY 0.489362 (-4710 5135);
PAINT MONO (-4710 5135);
FORCEPROP 0 LASTPIN (-4100 5125) $PN 5
J 0
(-4090 5135);
DISPLAY 0.489362 (-4090 5135);
PAINT MONO (-4090 5135);
FORCEPROP 0 LASTPIN (-4700 5175) $PN 1
J 2
(-4710 5185);
DISPLAY 0.489362 (-4710 5185);
PAINT MONO (-4710 5185);
FORCEPROP 0 LASTPIN (-4100 5175) $PN 4
J 0
(-4090 5185);
DISPLAY 0.489362 (-4090 5185);
PAINT MONO (-4090 5185);
FORCEPROP 1 LAST MATERIAL IC
J 0
(-4547 5248);
DISPLAY 0.489362 (-4547 5248);
PAINT SKYBLUE (-4547 5248);
FORCEPROP 2 LAST PART_TYPE SMLF
J 0
(-4525 5425);
DISPLAY 0.680851 (-4525 5425);
FORCEPROP 2 LAST VALUE 2N7002KDW
J 0
(-4525 5375);
DISPLAY 0.489362 (-4525 5375);
PAINT SKYBLUE (-4525 5375);
FORCEPROP 2 LAST CDS_LIB pure_quanta
J 0
(-4400 5125);
DISPLAY INVISIBLE (-4400 5125);
FORCEPROP 1 LAST CDS_LMAN_SYM_OUTLINE -150,100,150,-100
J 0
(-4400 5125);
DISPLAY 0.468085 (-4400 5125);
PAINT GREEN (-4400 5125);
DISPLAY INVISIBLE (-4400 5125);
FORCEPROP 1 LAST NEEDS_NO_SIZE TRUE
J 0
(-4400 5124);
DISPLAY 0.468085 (-4400 5124);
PAINT GREEN (-4400 5124);
DISPLAY INVISIBLE (-4400 5124);
FORCEPROP 1 LAST PATH I16
J 0
(-4400 5125);
DISPLAY 0.723404 (-4400 5125);
PAINT GREEN (-4400 5125);
DISPLAY INVISIBLE (-4400 5125);
FORCEPROP 1 LAST PART_NUMBER BAM70020047
J 0
(-4547 5292);
DISPLAY 0.489362 (-4547 5292);
PAINT SKYBLUE (-4547 5292);
DISPLAY INVISIBLE (-4547 5292);
FORCEADD UNIVERSAL_POWER..1
(-5100 4150);
FORCEPROP 3 LASTPIN (-5100 4100) SIG_NAME P3V3_AUX\g
J 0
(-5090 4110);
DISPLAY 0.659574 (-5090 4110);
PAINT MONO (-5090 4110);
DISPLAY INVISIBLE (-5090 4110);
FORCEPROP 1 LAST HDL_POWER P3V3_AUX
J 1
(-5100 4200);
DISPLAY 0.489362 (-5100 4200);
PAINT GREEN (-5100 4200);
FORCEPROP 2 LAST BOM_COST OCP3.0 
J 0
(-5100 4250);
DISPLAY 0.680851 (-5100 4250);
DISPLAY INVISIBLE (-5100 4250);
FORCEPROP 2 LAST CDS_LIB pure_quanta_power
J 0
(-5100 4150);
DISPLAY INVISIBLE (-5100 4150);
FORCEPROP 1 LAST PATH I17
J 0
(-5050 4175);
DISPLAY 0.872340 (-5050 4175);
PAINT AQUA (-5050 4175);
DISPLAY INVISIBLE (-5050 4175);
FORCEADD Q_RES..2
(-5100 3800);
FORCEPROP 1 LAST LOCATION R945
J 0
(-5055 3925);
DISPLAY 0.489362 (-5055 3925);
PAINT SKYBLUE (-5055 3925);
FORCEPROP 0 LAST $SEC 1
J 0
(-5050 3975);
DISPLAY 0.680851 (-5050 3975);
PAINT MONO (-5050 3975);
DISPLAY INVISIBLE (-5050 3975);
FORCEPROP 0 LAST CDS_SEC 1
J 0
(-5050 3975);
DISPLAY 0.680851 (-5050 3975);
DISPLAY INVISIBLE (-5050 3975);
FORCEPROP 1 LASTPIN (-5100 3900) $PN 1
J 0
(-5095 3862);
DISPLAY 0.489362 (-5095 3862);
PAINT MONO (-5095 3862);
FORCEPROP 1 LASTPIN (-5100 3700) $PN 2
J 0
(-5095 3710);
DISPLAY 0.489362 (-5095 3710);
PAINT MONO (-5095 3710);
FORCEPROP 1 LAST MATERIAL CHIP
J 0
(-5060 3725);
DISPLAY 0.489362 (-5060 3725);
PAINT SKYBLUE (-5060 3725);
FORCEPROP 1 LAST TOLERANCE 5%
J 0
(-5055 3825);
DISPLAY 0.489362 (-5055 3825);
PAINT SKYBLUE (-5055 3825);
FORCEPROP 1 LAST WATTAGE 1/16W
J 0
(-5060 3775);
DISPLAY 0.489362 (-5060 3775);
PAINT SKYBLUE (-5060 3775);
FORCEPROP 1 LAST VALUE 4.7K
J 0
(-5055 3875);
DISPLAY 0.489362 (-5055 3875);
PAINT SKYBLUE (-5055 3875);
FORCEPROP 1 LAST PACK_TYPE 0402LF
J 0
(-5060 3625);
DISPLAY 0.489362 (-5060 3625);
PAINT SKYBLUE (-5060 3625);
DISPLAY INVISIBLE (-5060 3625);
FORCEPROP 2 LAST BOM_COST OCP3.0 
J 0
(-5050 3975);
DISPLAY 0.680851 (-5050 3975);
DISPLAY INVISIBLE (-5050 3975);
FORCEPROP 2 LAST CDS_LIB pure_quanta
J 0
(-5100 3800);
DISPLAY INVISIBLE (-5100 3800);
FORCEPROP 1 LAST PATH I18
J 0
(-5050 3975);
DISPLAY 0.978723 (-5050 3975);
PAINT WHITE (-5050 3975);
DISPLAY INVISIBLE (-5050 3975);
FORCEPROP 1 LAST PART_NUMBER CS24702JB10
J 0
(-5060 3675);
DISPLAY 0.489362 (-5060 3675);
PAINT SKYBLUE (-5060 3675);
DISPLAY INVISIBLE (-5060 3675);
FORCEADD MOSFET_DUAL_6P..1
(-4550 3500);
FORCEPROP 1 LAST LOCATION Q11
J 0
(-4697 3709);
DISPLAY 0.489362 (-4697 3709);
PAINT SKYBLUE (-4697 3709);
FORCEPROP 0 LAST $SEC 1
J 0
(-4675 3850);
DISPLAY 0.680851 (-4675 3850);
PAINT MONO (-4675 3850);
DISPLAY INVISIBLE (-4675 3850);
FORCEPROP 0 LAST CDS_SEC 1
J 0
(-4675 3850);
DISPLAY 0.680851 (-4675 3850);
DISPLAY INVISIBLE (-4675 3850);
FORCEPROP 0 LASTPIN (-4850 3450) $PN 6
J 2
(-4860 3460);
DISPLAY 0.489362 (-4860 3460);
PAINT MONO (-4860 3460);
FORCEPROP 0 LASTPIN (-4250 3450) $PN 3
J 0
(-4240 3460);
DISPLAY 0.489362 (-4240 3460);
PAINT MONO (-4240 3460);
FORCEPROP 0 LASTPIN (-4850 3500) $PN 2
J 2
(-4860 3510);
DISPLAY 0.489362 (-4860 3510);
PAINT MONO (-4860 3510);
FORCEPROP 0 LASTPIN (-4250 3500) $PN 5
J 0
(-4240 3510);
DISPLAY 0.489362 (-4240 3510);
PAINT MONO (-4240 3510);
FORCEPROP 0 LASTPIN (-4850 3550) $PN 1
J 2
(-4860 3560);
DISPLAY 0.489362 (-4860 3560);
PAINT MONO (-4860 3560);
FORCEPROP 0 LASTPIN (-4250 3550) $PN 4
J 0
(-4240 3560);
DISPLAY 0.489362 (-4240 3560);
PAINT MONO (-4240 3560);
FORCEPROP 2 LAST PART_TYPE SMLF
J 0
(-4675 3800);
DISPLAY 0.680851 (-4675 3800);
FORCEPROP 1 LAST MATERIAL IC
J 0
(-4697 3623);
DISPLAY 0.489362 (-4697 3623);
PAINT SKYBLUE (-4697 3623);
FORCEPROP 2 LAST VALUE 2N7002KDW
J 0
(-4675 3750);
DISPLAY 0.489362 (-4675 3750);
PAINT SKYBLUE (-4675 3750);
FORCEPROP 2 LAST CDS_LIB pure_quanta
J 0
(-4550 3500);
DISPLAY INVISIBLE (-4550 3500);
FORCEPROP 1 LAST CDS_LMAN_SYM_OUTLINE -150,100,150,-100
J 0
(-4550 3500);
DISPLAY 0.468085 (-4550 3500);
PAINT GREEN (-4550 3500);
DISPLAY INVISIBLE (-4550 3500);
FORCEPROP 1 LAST NEEDS_NO_SIZE TRUE
J 0
(-4550 3499);
DISPLAY 0.468085 (-4550 3499);
PAINT GREEN (-4550 3499);
DISPLAY INVISIBLE (-4550 3499);
FORCEPROP 1 LAST PATH I19
J 0
(-4550 3500);
DISPLAY 0.723404 (-4550 3500);
PAINT GREEN (-4550 3500);
DISPLAY INVISIBLE (-4550 3500);
FORCEPROP 1 LAST PART_NUMBER BAM70020047
J 0
(-4697 3667);
DISPLAY 0.489362 (-4697 3667);
PAINT SKYBLUE (-4697 3667);
DISPLAY INVISIBLE (-4697 3667);
FORCEADD UNIVERSAL_POWER..1
(-2125 4100);
FORCEPROP 3 LASTPIN (-2125 4050) SIG_NAME P3V3_AUX\g
J 0
(-2115 4060);
DISPLAY 0.659574 (-2115 4060);
PAINT MONO (-2115 4060);
DISPLAY INVISIBLE (-2115 4060);
FORCEPROP 1 LAST HDL_POWER P3V3_AUX
J 1
(-2125 4150);
DISPLAY 0.489362 (-2125 4150);
PAINT GREEN (-2125 4150);
FORCEPROP 2 LAST BOM_COST OCP3.0 
J 0
(-2125 4200);
DISPLAY 0.680851 (-2125 4200);
DISPLAY INVISIBLE (-2125 4200);
FORCEPROP 2 LAST CDS_LIB pure_quanta_power
J 0
(-2125 4100);
DISPLAY INVISIBLE (-2125 4100);
FORCEPROP 1 LAST PATH I2
J 0
(-2075 4125);
DISPLAY 0.872340 (-2075 4125);
PAINT AQUA (-2075 4125);
DISPLAY INVISIBLE (-2075 4125);
FORCEADD GND..1
R 5
(-4925 3550);
FORCEPROP 3 LASTPIN (-4875 3550) SIG_NAME GND\g
J 0
(-4865 3560);
DISPLAY 0.659574 (-4865 3560);
PAINT MONO (-4865 3560);
DISPLAY INVISIBLE (-4865 3560);
FORCEPROP 2 LAST BOM_COST MEM
R 3
J 0
(-4850 3650);
DISPLAY 0.808511 (-4850 3650);
DISPLAY INVISIBLE (-4850 3650);
FORCEPROP 1 LAST SIZE 1B
R 3
J 0
(-4975 3475);
DISPLAY 0.851064 (-4975 3475);
PAINT GREEN (-4975 3475);
DISPLAY INVISIBLE (-4975 3475);
FORCEPROP 2 LAST CDS_LIB pure_quanta_power
J 0
(-4925 3550);
DISPLAY INVISIBLE (-4925 3550);
FORCEPROP 1 LAST HDL_POWER GND
R 3
J 0
(-4775 3550);
DISPLAY 0.851064 (-4775 3550);
PAINT GREEN (-4775 3550);
DISPLAY INVISIBLE (-4775 3550);
FORCEPROP 1 LAST PATH I20
R 3
J 0
(-4925 3475);
DISPLAY 0.872340 (-4925 3475);
PAINT AQUA (-4925 3475);
DISPLAY INVISIBLE (-4925 3475);
FORCEADD Q_RES..1
(-5675 5125);
FORCEPROP 1 LAST LOCATION R935
J 0
(-5625 5125);
DISPLAY 0.489362 (-5625 5125);
PAINT SKYBLUE (-5625 5125);
FORCEPROP 0 LAST $SEC 1
J 0
(-5625 5175);
DISPLAY 0.680851 (-5625 5175);
PAINT MONO (-5625 5175);
DISPLAY INVISIBLE (-5625 5175);
FORCEPROP 0 LAST CDS_SEC 1
J 0
(-5625 5175);
DISPLAY 0.680851 (-5625 5175);
DISPLAY INVISIBLE (-5625 5175);
FORCEPROP 1 LASTPIN (-5775 5125) $PN 1
J 0
(-5763 5137);
DISPLAY 0.489362 (-5763 5137);
PAINT MONO (-5763 5137);
FORCEPROP 1 LASTPIN (-5575 5125) $PN 2
J 0
(-5613 5137);
DISPLAY 0.489362 (-5613 5137);
PAINT MONO (-5613 5137);
FORCEPROP 1 LAST VALUE 0
J 2
(-5800 5125);
DISPLAY 0.489362 (-5800 5125);
PAINT SKYBLUE (-5800 5125);
FORCEPROP 2 LAST BOM_COST MEM
J 2
(-5650 5275);
DISPLAY 0.744681 (-5650 5275);
PAINT WHITE (-5650 5275);
DISPLAY INVISIBLE (-5650 5275);
FORCEPROP 2 LAST CDS_LIB pure_quanta
J 0
(-5675 5125);
DISPLAY INVISIBLE (-5675 5125);
FORCEPROP 1 LAST WATTAGE 1/16W
J 2
(-5750 5050);
DISPLAY 0.489362 (-5750 5050);
PAINT SKYBLUE (-5750 5050);
DISPLAY INVISIBLE (-5750 5050);
FORCEPROP 1 LAST MATERIAL CHIP
J 2
(-5500 5100);
DISPLAY 0.489362 (-5500 5100);
PAINT SKYBLUE (-5500 5100);
DISPLAY INVISIBLE (-5500 5100);
FORCEPROP 1 LAST TOLERANCE 5%
J 0
(-5800 5100);
DISPLAY 0.489362 (-5800 5100);
PAINT SKYBLUE (-5800 5100);
DISPLAY INVISIBLE (-5800 5100);
FORCEPROP 1 LAST PACK_TYPE 0402LF
J 2
(-5500 5050);
DISPLAY 0.489362 (-5500 5050);
PAINT SKYBLUE (-5500 5050);
DISPLAY INVISIBLE (-5500 5050);
FORCEPROP 1 LAST PATH I21
J 0
(-5725 5275);
DISPLAY 0.978723 (-5725 5275);
PAINT WHITE (-5725 5275);
DISPLAY INVISIBLE (-5725 5275);
FORCEPROP 1 LAST PART_NUMBER CS00002JB13
J 2
(-5575 5175);
DISPLAY 0.489362 (-5575 5175);
PAINT SKYBLUE (-5575 5175);
DISPLAY INVISIBLE (-5575 5175);
FORCEADD Q_RES..1
(-5825 3500);
FORCEPROP 1 LAST LOCATION R936
J 0
(-5775 3450);
DISPLAY 0.489362 (-5775 3450);
PAINT SKYBLUE (-5775 3450);
FORCEPROP 0 LAST $SEC 1
J 0
(-5775 3550);
DISPLAY 0.680851 (-5775 3550);
PAINT MONO (-5775 3550);
DISPLAY INVISIBLE (-5775 3550);
FORCEPROP 0 LAST CDS_SEC 1
J 0
(-5775 3550);
DISPLAY 0.680851 (-5775 3550);
DISPLAY INVISIBLE (-5775 3550);
FORCEPROP 1 LASTPIN (-5925 3500) $PN 1
J 0
(-5913 3512);
DISPLAY 0.489362 (-5913 3512);
PAINT MONO (-5913 3512);
FORCEPROP 1 LASTPIN (-5725 3500) $PN 2
J 0
(-5763 3512);
DISPLAY 0.489362 (-5763 3512);
PAINT MONO (-5763 3512);
FORCEPROP 1 LAST VALUE 0
J 2
(-5950 3500);
DISPLAY 0.489362 (-5950 3500);
PAINT SKYBLUE (-5950 3500);
FORCEPROP 2 LASTPIN (-5725 3500) SIG_NAME FM_SMERR_BUF_R_LED_N
J 0
(-5660 3510);
DISPLAY 0.489362 (-5660 3510);
FORCEPROP 2 LASTPROP $XRERR UNIQUE?
J 0
(-5900 3510);
DISPLAY 0.638298 (-5900 3510);
PAINT MONO (-5900 3510);
DISPLAY INVISIBLE (-5900 3510);
FORCEPROP 2 LAST BOM_COST MEM
J 2
(-5800 3650);
DISPLAY 0.744681 (-5800 3650);
PAINT WHITE (-5800 3650);
DISPLAY INVISIBLE (-5800 3650);
FORCEPROP 2 LAST CDS_LIB pure_quanta
J 0
(-5825 3500);
DISPLAY INVISIBLE (-5825 3500);
FORCEPROP 1 LAST WATTAGE 1/16W
J 2
(-5900 3425);
DISPLAY 0.489362 (-5900 3425);
PAINT SKYBLUE (-5900 3425);
DISPLAY INVISIBLE (-5900 3425);
FORCEPROP 1 LAST MATERIAL CHIP
J 2
(-5650 3475);
DISPLAY 0.489362 (-5650 3475);
PAINT SKYBLUE (-5650 3475);
DISPLAY INVISIBLE (-5650 3475);
FORCEPROP 1 LAST TOLERANCE 5%
J 0
(-5950 3475);
DISPLAY 0.489362 (-5950 3475);
PAINT SKYBLUE (-5950 3475);
DISPLAY INVISIBLE (-5950 3475);
FORCEPROP 1 LAST PACK_TYPE 0402LF
J 2
(-5650 3425);
DISPLAY 0.489362 (-5650 3425);
PAINT SKYBLUE (-5650 3425);
DISPLAY INVISIBLE (-5650 3425);
FORCEPROP 1 LAST PATH I22
J 0
(-5875 3650);
DISPLAY 0.978723 (-5875 3650);
PAINT WHITE (-5875 3650);
DISPLAY INVISIBLE (-5875 3650);
FORCEPROP 1 LAST PART_NUMBER CS00002JB13
J 2
(-5725 3550);
DISPLAY 0.489362 (-5725 3550);
PAINT SKYBLUE (-5725 3550);
DISPLAY INVISIBLE (-5725 3550);
FORCEADD Q_CAP..1
(-7200 5450);
FORCEPROP 1 LAST LOCATION C218
J 0
(-7150 5550);
DISPLAY 0.489362 (-7150 5550);
PAINT SKYBLUE (-7150 5550);
FORCEPROP 0 LAST $SEC 1
J 0
(-7150 5600);
DISPLAY 0.680851 (-7150 5600);
PAINT MONO (-7150 5600);
DISPLAY INVISIBLE (-7150 5600);
FORCEPROP 0 LAST CDS_SEC 1
J 0
(-7150 5600);
DISPLAY 0.680851 (-7150 5600);
DISPLAY INVISIBLE (-7150 5600);
FORCEPROP 1 LASTPIN (-7200 5550) $PN 1
J 0
(-7190 5530);
DISPLAY 0.489362 (-7190 5530);
PAINT MONO (-7190 5530);
FORCEPROP 1 LASTPIN (-7200 5350) $PN 2
J 0
(-7190 5330);
DISPLAY 0.489362 (-7190 5330);
PAINT MONO (-7190 5330);
FORCEPROP 1 LAST VALUE 0.1UF
J 0
(-7125 5525);
DISPLAY 0.489362 (-7125 5525);
PAINT SKYBLUE (-7125 5525);
FORCEPROP 1 LAST PACK_TYPE 0402
J 0
(-7125 5275);
DISPLAY 0.489362 (-7125 5275);
PAINT SKYBLUE (-7125 5275);
FORCEPROP 1 LAST MATERIAL X7R
J 0
(-7125 5375);
DISPLAY 0.489362 (-7125 5375);
PAINT SKYBLUE (-7125 5375);
FORCEPROP 1 LAST TOLERANCE 10%
J 0
(-7125 5425);
DISPLAY 0.489362 (-7125 5425);
PAINT SKYBLUE (-7125 5425);
FORCEPROP 1 LAST VOLTAGE 25V
J 0
(-7125 5475);
DISPLAY 0.489362 (-7125 5475);
PAINT SKYBLUE (-7125 5475);
FORCEPROP 2 LAST CDS_LIB pure_quanta
J 0
(-7200 5450);
DISPLAY INVISIBLE (-7200 5450);
FORCEPROP 2 LAST BOM_COST OCP3.0 
J 0
(-7175 5575);
DISPLAY 0.680851 (-7175 5575);
DISPLAY INVISIBLE (-7175 5575);
FORCEPROP 1 LAST PATH I24
J 0
(-7150 5600);
DISPLAY 0.978723 (-7150 5600);
PAINT WHITE (-7150 5600);
DISPLAY INVISIBLE (-7150 5600);
FORCEPROP 1 LAST PART_NUMBER CH4104K1B00
J 0
(-7125 5325);
DISPLAY 0.489362 (-7125 5325);
PAINT SKYBLUE (-7125 5325);
DISPLAY INVISIBLE (-7125 5325);
FORCEADD UNIVERSAL_GND..1
(-7200 5250);
FORCEPROP 3 LASTPIN (-7200 5300) SIG_NAME GND\g
J 0
(-7190 5310);
DISPLAY 0.659574 (-7190 5310);
PAINT MONO (-7190 5310);
DISPLAY INVISIBLE (-7190 5310);
FORCEPROP 2 LAST BOM_COST OCP3.0 
J 0
(-7400 5325);
DISPLAY 0.680851 (-7400 5325);
DISPLAY INVISIBLE (-7400 5325);
FORCEPROP 2 LAST CDS_LIB pure_quanta_power
J 0
(-7200 5250);
DISPLAY INVISIBLE (-7200 5250);
FORCEPROP 1 LAST HDL_POWER GND
J 1
(-7175 5175);
DISPLAY 0.872340 (-7175 5175);
PAINT GREEN (-7175 5175);
DISPLAY INVISIBLE (-7175 5175);
FORCEPROP 1 LAST PATH I25
J 0
(-7125 5250);
DISPLAY 0.872340 (-7125 5250);
PAINT AQUA (-7125 5250);
DISPLAY INVISIBLE (-7125 5250);
FORCEADD SN74LVC1G07DBVR..1
(-6600 5125);
FORCEPROP 1 LAST LOCATION U82
J 0
(-6725 5380);
DISPLAY 0.489362 (-6725 5380);
PAINT SKYBLUE (-6725 5380);
FORCEPROP 0 LAST $SEC 1
J 0
(-6725 5525);
DISPLAY 0.680851 (-6725 5525);
PAINT MONO (-6725 5525);
DISPLAY INVISIBLE (-6725 5525);
FORCEPROP 0 LAST CDS_SEC 1
J 0
(-6725 5525);
DISPLAY 0.680851 (-6725 5525);
DISPLAY INVISIBLE (-6725 5525);
FORCEPROP 0 LASTPIN (-6775 5125) $PN 2
J 2
(-6785 5135);
DISPLAY 0.489362 (-6785 5135);
PAINT MONO (-6785 5135);
FORCEPROP 0 LASTPIN (-6775 5025) $PN 3
J 2
(-6785 5035);
DISPLAY 0.489362 (-6785 5035);
PAINT MONO (-6785 5035);
FORCEPROP 0 LASTPIN (-6425 5025) $PN 1
J 0
(-6415 5035);
DISPLAY 0.489362 (-6415 5035);
PAINT MONO (-6415 5035);
FORCEPROP 0 LASTPIN (-6775 5225) $PN 5
J 2
(-6785 5235);
DISPLAY 0.489362 (-6785 5235);
PAINT MONO (-6785 5235);
FORCEPROP 0 LASTPIN (-6425 5125) $PN 4
J 0
(-6415 5135);
DISPLAY 0.489362 (-6415 5135);
PAINT MONO (-6415 5135);
FORCEPROP 1 LAST MATERIAL IC
J 0
(-6725 5285);
DISPLAY 0.489362 (-6725 5285);
PAINT SKYBLUE (-6725 5285);
FORCEPROP 2 LAST VALUE SN74LVC1G07DBVR
J 0
(-6725 5475);
DISPLAY 0.489362 (-6725 5475);
PAINT SKYBLUE (-6725 5475);
FORCEPROP 2 LAST PACK_TYPE SMLF
J 0
(-6725 5425);
DISPLAY 0.489362 (-6725 5425);
PAINT SKYBLUE (-6725 5425);
FORCEPROP 2 LAST CDS_LIB pure_quanta
J 0
(-6600 5125);
DISPLAY INVISIBLE (-6600 5125);
FORCEPROP 1 LAST NEEDS_NO_SIZE TRUE
J 0
(-6600 5125);
DISPLAY 0.468085 (-6600 5125);
PAINT GREEN (-6600 5125);
DISPLAY INVISIBLE (-6600 5125);
FORCEPROP 1 LAST PATH I26
J 0
(-6500 5280);
DISPLAY 0.723404 (-6500 5280);
PAINT GREEN (-6500 5280);
DISPLAY INVISIBLE (-6500 5280);
FORCEPROP 1 LAST PART_NUMBER AL1G0007024
J 0
(-6725 5335);
DISPLAY 0.489362 (-6725 5335);
PAINT SKYBLUE (-6725 5335);
DISPLAY INVISIBLE (-6725 5335);
FORCEADD UNIVERSAL_GND..1
(-6850 4850);
FORCEPROP 3 LASTPIN (-6850 4900) SIG_NAME GND\g
J 0
(-6840 4910);
DISPLAY 0.659574 (-6840 4910);
PAINT MONO (-6840 4910);
DISPLAY INVISIBLE (-6840 4910);
FORCEPROP 2 LAST BOM_COST OCP3.0 
J 0
(-7050 4925);
DISPLAY 0.680851 (-7050 4925);
DISPLAY INVISIBLE (-7050 4925);
FORCEPROP 2 LAST CDS_LIB pure_quanta_power
J 0
(-6850 4850);
DISPLAY INVISIBLE (-6850 4850);
FORCEPROP 1 LAST HDL_POWER GND
J 1
(-6825 4775);
DISPLAY 0.872340 (-6825 4775);
PAINT GREEN (-6825 4775);
DISPLAY INVISIBLE (-6825 4775);
FORCEPROP 1 LAST PATH I27
J 0
(-6775 4850);
DISPLAY 0.872340 (-6775 4850);
PAINT AQUA (-6775 4850);
DISPLAY INVISIBLE (-6775 4850);
FORCEADD P1V0..1
(-7350 4125);
FORCEPROP 3 LASTPIN (-7350 4075) SIG_NAME P1V8_AUX\g
J 0
(-7340 4085);
DISPLAY 0.659574 (-7340 4085);
PAINT MONO (-7340 4085);
DISPLAY INVISIBLE (-7340 4085);
FORCEPROP 1 LAST HDL_POWER P1V8_AUX
J 1
(-7350 4175);
DISPLAY 0.489362 (-7350 4175);
PAINT GREEN (-7350 4175);
FORCEPROP 2 LAST CDS_LIB pure_quanta_power
J 0
(-7350 4125);
DISPLAY INVISIBLE (-7350 4125);
FORCEPROP 1 LAST PATH I28
J 0
(-7300 4150);
DISPLAY 0.872340 (-7300 4150);
PAINT AQUA (-7300 4150);
DISPLAY INVISIBLE (-7300 4150);
FORCEADD Q_CAP..1
(-7350 3825);
FORCEPROP 1 LAST LOCATION C219
J 0
(-7300 3925);
DISPLAY 0.489362 (-7300 3925);
PAINT SKYBLUE (-7300 3925);
FORCEPROP 0 LAST $SEC 1
J 0
(-7300 3975);
DISPLAY 0.680851 (-7300 3975);
PAINT MONO (-7300 3975);
DISPLAY INVISIBLE (-7300 3975);
FORCEPROP 0 LAST CDS_SEC 1
J 0
(-7300 3975);
DISPLAY 0.680851 (-7300 3975);
DISPLAY INVISIBLE (-7300 3975);
FORCEPROP 1 LASTPIN (-7350 3925) $PN 1
J 0
(-7340 3905);
DISPLAY 0.489362 (-7340 3905);
PAINT MONO (-7340 3905);
FORCEPROP 1 LASTPIN (-7350 3725) $PN 2
J 0
(-7340 3705);
DISPLAY 0.489362 (-7340 3705);
PAINT MONO (-7340 3705);
FORCEPROP 1 LAST MATERIAL X7R
J 0
(-7275 3750);
DISPLAY 0.489362 (-7275 3750);
PAINT SKYBLUE (-7275 3750);
FORCEPROP 1 LAST PACK_TYPE 0402
J 0
(-7275 3650);
DISPLAY 0.489362 (-7275 3650);
PAINT SKYBLUE (-7275 3650);
FORCEPROP 1 LAST TOLERANCE 10%
J 0
(-7275 3800);
DISPLAY 0.489362 (-7275 3800);
PAINT SKYBLUE (-7275 3800);
FORCEPROP 1 LAST VALUE 0.1UF
J 0
(-7275 3900);
DISPLAY 0.489362 (-7275 3900);
PAINT SKYBLUE (-7275 3900);
FORCEPROP 1 LAST VOLTAGE 25V
J 0
(-7275 3850);
DISPLAY 0.489362 (-7275 3850);
PAINT SKYBLUE (-7275 3850);
FORCEPROP 2 LAST CDS_LIB pure_quanta
J 0
(-7350 3825);
DISPLAY INVISIBLE (-7350 3825);
FORCEPROP 2 LAST BOM_COST OCP3.0 
J 0
(-7325 3950);
DISPLAY 0.680851 (-7325 3950);
DISPLAY INVISIBLE (-7325 3950);
FORCEPROP 1 LAST PATH I29
J 0
(-7300 3975);
DISPLAY 0.978723 (-7300 3975);
PAINT WHITE (-7300 3975);
DISPLAY INVISIBLE (-7300 3975);
FORCEPROP 1 LAST PART_NUMBER CH4104K1B00
J 0
(-7275 3700);
DISPLAY 0.489362 (-7275 3700);
PAINT SKYBLUE (-7275 3700);
DISPLAY INVISIBLE (-7275 3700);
FORCEADD Q_RES..1
(-2250 3450);
FORCEPROP 1 LAST LOCATION R950
J 0
(-2300 3500);
DISPLAY 0.489362 (-2300 3500);
PAINT SKYBLUE (-2300 3500);
FORCEPROP 0 LAST $SEC 1
J 0
(-2300 3550);
DISPLAY 0.680851 (-2300 3550);
PAINT MONO (-2300 3550);
DISPLAY INVISIBLE (-2300 3550);
FORCEPROP 0 LAST CDS_SEC 1
J 0
(-2300 3550);
DISPLAY 0.680851 (-2300 3550);
DISPLAY INVISIBLE (-2300 3550);
FORCEPROP 1 LASTPIN (-2350 3450) $PN 1
J 0
(-2338 3462);
DISPLAY 0.489362 (-2338 3462);
PAINT MONO (-2338 3462);
FORCEPROP 1 LASTPIN (-2150 3450) $PN 2
J 0
(-2188 3462);
DISPLAY 0.489362 (-2188 3462);
PAINT MONO (-2188 3462);
FORCEPROP 1 LAST WATTAGE 1/16W
J 2
(-2175 3375);
DISPLAY 0.489362 (-2175 3375);
PAINT SKYBLUE (-2175 3375);
FORCEPROP 1 LAST MATERIAL CHIP
J 0
(-2150 3375);
DISPLAY 0.489362 (-2150 3375);
PAINT SKYBLUE (-2150 3375);
FORCEPROP 1 LAST TOLERANCE 1%
J 0
(-2375 3375);
DISPLAY 0.489362 (-2375 3375);
PAINT SKYBLUE (-2375 3375);
FORCEPROP 1 LAST PACK_TYPE 0402LF
J 0
(-2025 3375);
DISPLAY 0.489362 (-2025 3375);
PAINT SKYBLUE (-2025 3375);
FORCEPROP 1 LAST VALUE 249
J 2
(-2400 3375);
DISPLAY 0.489362 (-2400 3375);
PAINT SKYBLUE (-2400 3375);
FORCEPROP 2 LAST CDS_LIB pure_quanta
J 0
(-2250 3450);
DISPLAY INVISIBLE (-2250 3450);
FORCEPROP 1 LAST PATH I3
J 0
(-2300 3600);
DISPLAY 0.978723 (-2300 3600);
PAINT WHITE (-2300 3600);
DISPLAY INVISIBLE (-2300 3600);
FORCEPROP 1 LAST PART_NUMBER CS12492FB02
J 0
(-2225 3500);
DISPLAY 0.638298 (-2225 3500);
PAINT SKYBLUE (-2225 3500);
DISPLAY INVISIBLE (-2225 3500);
FORCEADD UNIVERSAL_GND..1
(-7350 3625);
FORCEPROP 3 LASTPIN (-7350 3675) SIG_NAME GND\g
J 0
(-7340 3685);
DISPLAY 0.659574 (-7340 3685);
PAINT MONO (-7340 3685);
DISPLAY INVISIBLE (-7340 3685);
FORCEPROP 2 LAST BOM_COST OCP3.0 
J 0
(-7550 3700);
DISPLAY 0.680851 (-7550 3700);
DISPLAY INVISIBLE (-7550 3700);
FORCEPROP 2 LAST CDS_LIB pure_quanta_power
J 0
(-7350 3625);
DISPLAY INVISIBLE (-7350 3625);
FORCEPROP 1 LAST HDL_POWER GND
J 1
(-7325 3550);
DISPLAY 0.872340 (-7325 3550);
PAINT GREEN (-7325 3550);
DISPLAY INVISIBLE (-7325 3550);
FORCEPROP 1 LAST PATH I30
J 0
(-7275 3625);
DISPLAY 0.872340 (-7275 3625);
PAINT AQUA (-7275 3625);
DISPLAY INVISIBLE (-7275 3625);
FORCEADD SN74LVC1G07DBVR..1
(-6750 3500);
FORCEPROP 1 LAST LOCATION U86
J 0
(-6875 3755);
DISPLAY 0.489362 (-6875 3755);
PAINT SKYBLUE (-6875 3755);
FORCEPROP 0 LAST $SEC 1
J 0
(-6875 3900);
DISPLAY 0.680851 (-6875 3900);
PAINT MONO (-6875 3900);
DISPLAY INVISIBLE (-6875 3900);
FORCEPROP 0 LAST CDS_SEC 1
J 0
(-6875 3900);
DISPLAY 0.680851 (-6875 3900);
DISPLAY INVISIBLE (-6875 3900);
FORCEPROP 0 LASTPIN (-6925 3500) $PN 2
J 2
(-6935 3510);
DISPLAY 0.489362 (-6935 3510);
PAINT MONO (-6935 3510);
FORCEPROP 0 LASTPIN (-6925 3400) $PN 3
J 2
(-6935 3410);
DISPLAY 0.489362 (-6935 3410);
PAINT MONO (-6935 3410);
FORCEPROP 0 LASTPIN (-6575 3400) $PN 1
J 0
(-6565 3410);
DISPLAY 0.489362 (-6565 3410);
PAINT MONO (-6565 3410);
FORCEPROP 0 LASTPIN (-6925 3600) $PN 5
J 2
(-6935 3610);
DISPLAY 0.489362 (-6935 3610);
PAINT MONO (-6935 3610);
FORCEPROP 0 LASTPIN (-6575 3500) $PN 4
J 0
(-6565 3510);
DISPLAY 0.489362 (-6565 3510);
PAINT MONO (-6565 3510);
FORCEPROP 1 LAST MATERIAL IC
J 0
(-6875 3660);
DISPLAY 0.489362 (-6875 3660);
PAINT SKYBLUE (-6875 3660);
FORCEPROP 2 LAST VALUE SN74LVC1G07DBVR
J 0
(-6875 3850);
DISPLAY 0.489362 (-6875 3850);
PAINT SKYBLUE (-6875 3850);
FORCEPROP 2 LAST PACK_TYPE SMLF
J 0
(-6875 3800);
DISPLAY 0.489362 (-6875 3800);
PAINT SKYBLUE (-6875 3800);
FORCEPROP 2 LAST CDS_LIB pure_quanta
J 0
(-6750 3500);
DISPLAY INVISIBLE (-6750 3500);
FORCEPROP 1 LAST NEEDS_NO_SIZE TRUE
J 0
(-6750 3500);
DISPLAY 0.468085 (-6750 3500);
PAINT GREEN (-6750 3500);
DISPLAY INVISIBLE (-6750 3500);
FORCEPROP 1 LAST PATH I31
J 0
(-6650 3655);
DISPLAY 0.723404 (-6650 3655);
PAINT GREEN (-6650 3655);
DISPLAY INVISIBLE (-6650 3655);
FORCEPROP 1 LAST PART_NUMBER AL1G0007024
J 0
(-6875 3710);
DISPLAY 0.489362 (-6875 3710);
PAINT SKYBLUE (-6875 3710);
DISPLAY INVISIBLE (-6875 3710);
FORCEADD UNIVERSAL_GND..1
(-7000 3225);
FORCEPROP 3 LASTPIN (-7000 3275) SIG_NAME GND\g
J 0
(-6990 3285);
DISPLAY 0.659574 (-6990 3285);
PAINT MONO (-6990 3285);
DISPLAY INVISIBLE (-6990 3285);
FORCEPROP 2 LAST CDS_LIB pure_quanta_power
J 0
(-7000 3225);
DISPLAY INVISIBLE (-7000 3225);
FORCEPROP 2 LAST BOM_COST OCP3.0 
J 0
(-7200 3300);
DISPLAY 0.680851 (-7200 3300);
DISPLAY INVISIBLE (-7200 3300);
FORCEPROP 1 LAST HDL_POWER GND
J 1
(-6975 3150);
DISPLAY 0.872340 (-6975 3150);
PAINT GREEN (-6975 3150);
DISPLAY INVISIBLE (-6975 3150);
FORCEPROP 1 LAST PATH I32
J 0
(-6925 3225);
DISPLAY 0.872340 (-6925 3225);
PAINT AQUA (-6925 3225);
DISPLAY INVISIBLE (-6925 3225);
FORCEADD Q_RES..1
(-7950 5125);
FORCEPROP 1 LAST LOCATION R934
J 0
(-8000 5175);
DISPLAY 0.489362 (-8000 5175);
PAINT SKYBLUE (-8000 5175);
FORCEPROP 0 LAST $SEC 1
J 0
(-8000 5225);
DISPLAY 0.680851 (-8000 5225);
PAINT MONO (-8000 5225);
DISPLAY INVISIBLE (-8000 5225);
FORCEPROP 0 LAST CDS_SEC 1
J 0
(-8000 5225);
DISPLAY 0.680851 (-8000 5225);
DISPLAY INVISIBLE (-8000 5225);
FORCEPROP 1 LASTPIN (-8050 5125) $PN 1
J 0
(-8038 5137);
DISPLAY 0.489362 (-8038 5137);
PAINT MONO (-8038 5137);
FORCEPROP 1 LASTPIN (-7850 5125) $PN 2
J 0
(-7888 5137);
DISPLAY 0.489362 (-7888 5137);
PAINT MONO (-7888 5137);
FORCEPROP 1 LAST VALUE 0
J 2
(-8075 5125);
DISPLAY 0.489362 (-8075 5125);
PAINT SKYBLUE (-8075 5125);
FORCEPROP 2 LAST BOM_COST MEM
J 2
(-7925 5275);
DISPLAY 0.744681 (-7925 5275);
PAINT WHITE (-7925 5275);
DISPLAY INVISIBLE (-7925 5275);
FORCEPROP 2 LAST CDS_LIB pure_quanta
J 0
(-7950 5125);
DISPLAY INVISIBLE (-7950 5125);
FORCEPROP 1 LAST WATTAGE 1/16W
J 2
(-8025 5050);
DISPLAY 0.489362 (-8025 5050);
PAINT SKYBLUE (-8025 5050);
DISPLAY INVISIBLE (-8025 5050);
FORCEPROP 1 LAST MATERIAL CHIP
J 2
(-7775 5100);
DISPLAY 0.489362 (-7775 5100);
PAINT SKYBLUE (-7775 5100);
DISPLAY INVISIBLE (-7775 5100);
FORCEPROP 1 LAST TOLERANCE 5%
J 0
(-8075 5100);
DISPLAY 0.489362 (-8075 5100);
PAINT SKYBLUE (-8075 5100);
DISPLAY INVISIBLE (-8075 5100);
FORCEPROP 1 LAST PACK_TYPE 0402LF
J 2
(-7775 5050);
DISPLAY 0.489362 (-7775 5050);
PAINT SKYBLUE (-7775 5050);
DISPLAY INVISIBLE (-7775 5050);
FORCEPROP 1 LAST PATH I33
J 0
(-8000 5275);
DISPLAY 0.978723 (-8000 5275);
PAINT WHITE (-8000 5275);
DISPLAY INVISIBLE (-8000 5275);
FORCEPROP 1 LAST PART_NUMBER CS00002JB13
J 2
(-7850 5175);
DISPLAY 0.489362 (-7850 5175);
PAINT SKYBLUE (-7850 5175);
DISPLAY INVISIBLE (-7850 5175);
FORCEADD Q_RES..1
(-7950 4875);
FORCEPROP 1 LAST LOCATION R941
J 0
(-8125 4900);
DISPLAY 0.489362 (-8125 4900);
PAINT SKYBLUE (-8125 4900);
FORCEPROP 0 LAST $SEC 1
J 0
(-8125 4950);
DISPLAY 0.680851 (-8125 4950);
PAINT MONO (-8125 4950);
DISPLAY INVISIBLE (-8125 4950);
FORCEPROP 0 LAST CDS_SEC 1
J 0
(-8125 4950);
DISPLAY 0.680851 (-8125 4950);
DISPLAY INVISIBLE (-8125 4950);
FORCEPROP 1 LASTPIN (-8050 4875) $PN 1
J 0
(-8038 4887);
DISPLAY 0.489362 (-8038 4887);
PAINT MONO (-8038 4887);
FORCEPROP 1 LASTPIN (-7850 4875) $PN 2
J 0
(-7888 4887);
DISPLAY 0.489362 (-7888 4887);
PAINT MONO (-7888 4887);
FORCEPROP 1 LAST VALUE 0
J 2
(-7750 4875);
DISPLAY 0.489362 (-7750 4875);
PAINT SKYBLUE (-7750 4875);
FORCEPROP 1 LAST MATERIAL EMPTY
J 0
(-7750 4900);
DISPLAY 0.489362 (-7750 4900);
PAINT RED (-7750 4900);
FORCEPROP 1 LAST PACK_TYPE 0402LF
J 0
(-7700 4725);
DISPLAY 0.978723 (-7700 4725);
PAINT SKYBLUE (-7700 4725);
DISPLAY INVISIBLE (-7700 4725);
FORCEPROP 1 LAST TOLERANCE 5%
J 0
(-7950 4775);
DISPLAY 0.978723 (-7950 4775);
PAINT SKYBLUE (-7950 4775);
DISPLAY INVISIBLE (-7950 4775);
FORCEPROP 1 LAST WATTAGE 1/16W
J 2
(-7975 4725);
DISPLAY 0.978723 (-7975 4725);
PAINT SKYBLUE (-7975 4725);
DISPLAY INVISIBLE (-7975 4725);
FORCEPROP 2 LAST CDS_LIB pure_quanta
J 0
(-7950 4875);
DISPLAY INVISIBLE (-7950 4875);
FORCEPROP 1 LAST PATH I34
J 0
(-8000 5025);
DISPLAY 0.978723 (-8000 5025);
PAINT WHITE (-8000 5025);
DISPLAY INVISIBLE (-8000 5025);
FORCEPROP 1 LAST PART_NUMBER CS00002JB13
J 0
(-8000 5000);
DISPLAY 0.978723 (-8000 5000);
PAINT SKYBLUE (-8000 5000);
DISPLAY INVISIBLE (-8000 5000);
FORCEADD OFFPAGE..1
(-8550 3500);
FORCEPROP 2 LAST $XR0 81 
J 0
(-8771 3500);
DISPLAY 0.638298 (-8771 3500);
PAINT MONO (-8771 3500);
FORCEPROP 2 LAST CDS_LIB standard
J 0
(-8550 3500);
DISPLAY INVISIBLE (-8550 3500);
FORCEPROP 1 LAST OFFPAGE TRUE
J 0
(-8225 3375);
DISPLAY 0.872340 (-8225 3375);
PAINT GREEN (-8225 3375);
DISPLAY INVISIBLE (-8225 3375);
FORCEPROP 1 LAST COMMENT_BODY TRUE
J 0
(-8425 3400);
DISPLAY 0.872340 (-8425 3400);
PAINT GREEN (-8425 3400);
DISPLAY INVISIBLE (-8425 3400);
FORCEPROP 2 LAST PATH I35
J 0
(-8750 3550);
DISPLAY 0.680851 (-8750 3550);
DISPLAY INVISIBLE (-8750 3550);
FORCEADD OFFPAGE..1
(-8700 4875);
FORCEPROP 2 LAST $XR0 28 
J 0
(-8921 4875);
DISPLAY 0.638298 (-8921 4875);
PAINT MONO (-8921 4875);
FORCEPROP 2 LAST CDS_LIB standard
J 0
(-8700 4875);
DISPLAY INVISIBLE (-8700 4875);
FORCEPROP 1 LAST OFFPAGE TRUE
J 0
(-8375 4750);
DISPLAY 0.872340 (-8375 4750);
PAINT GREEN (-8375 4750);
DISPLAY INVISIBLE (-8375 4750);
FORCEPROP 1 LAST COMMENT_BODY TRUE
J 0
(-8575 4775);
DISPLAY 0.872340 (-8575 4775);
PAINT GREEN (-8575 4775);
DISPLAY INVISIBLE (-8575 4775);
FORCEPROP 2 LAST PATH I36
J 0
(-8950 4925);
DISPLAY 0.680851 (-8950 4925);
DISPLAY INVISIBLE (-8950 4925);
FORCEADD OFFPAGE..1
(-9025 5125);
FORCEPROP 2 LAST $XR1 34 
J 0
(-9336 5125);
DISPLAY 0.638298 (-9336 5125);
PAINT MONO (-9336 5125);
FORCEPROP 2 LAST $XR0 28 
J 0
(-9246 5125);
DISPLAY 0.638298 (-9246 5125);
PAINT MONO (-9246 5125);
FORCEPROP 2 LAST CDS_LIB standard
J 0
(-9025 5125);
DISPLAY INVISIBLE (-9025 5125);
FORCEPROP 1 LAST OFFPAGE TRUE
J 0
(-8700 5000);
DISPLAY 0.872340 (-8700 5000);
PAINT GREEN (-8700 5000);
DISPLAY INVISIBLE (-8700 5000);
FORCEPROP 1 LAST COMMENT_BODY TRUE
J 0
(-8900 5025);
DISPLAY 0.872340 (-8900 5025);
PAINT GREEN (-8900 5025);
DISPLAY INVISIBLE (-8900 5025);
FORCEPROP 2 LAST PATH I37
J 0
(-9225 5175);
DISPLAY 0.680851 (-9225 5175);
DISPLAY INVISIBLE (-9225 5175);
FORCEADD Q_LED..1
R 2
(-4275 550);
FORCEPROP 1 LAST LOCATION D49
J 2
(-4175 735);
DISPLAY 0.489362 (-4175 735);
PAINT SKYBLUE (-4175 735);
FORCEPROP 0 LAST $SEC 1
J 0
(-4175 925);
DISPLAY 0.680851 (-4175 925);
PAINT MONO (-4175 925);
DISPLAY INVISIBLE (-4175 925);
FORCEPROP 0 LAST CDS_SEC 1
J 0
(-4175 925);
DISPLAY 0.680851 (-4175 925);
DISPLAY INVISIBLE (-4175 925);
FORCEPROP 0 LASTPIN (-4125 550) $PN A
J 0
(-4115 560);
DISPLAY 0.489362 (-4115 560);
PAINT MONO (-4115 560);
FORCEPROP 0 LASTPIN (-4425 550) $PN C
J 2
(-4435 560);
DISPLAY 0.489362 (-4435 560);
PAINT MONO (-4435 560);
FORCEPROP 2 LAST COLOR LED_BLUE
J 2
(-4175 875);
DISPLAY 0.489362 (-4175 875);
FORCEPROP 1 LAST MATERIAL IC
J 2
(-4175 630);
DISPLAY 0.489362 (-4175 630);
PAINT SKYBLUE (-4175 630);
FORCEPROP 2 LAST MANUF_PN LTST-C281TBKT-5A
J 2
(-4175 825);
DISPLAY 0.680851 (-4175 825);
FORCEPROP 2 LAST PACK_TYPE SMLF
J 2
(-4175 775);
DISPLAY 0.489362 (-4175 775);
PAINT SKYBLUE (-4175 775);
FORCEPROP 1 LAST NEEDS_NO_SIZE TRUE
J 2
(-4275 550);
DISPLAY 0.468085 (-4275 550);
PAINT GREEN (-4275 550);
DISPLAY INVISIBLE (-4275 550);
FORCEPROP 2 LAST CDS_LIB pure_quanta
J 2
(-4275 550);
DISPLAY INVISIBLE (-4275 550);
FORCEPROP 1 LAST PATH I38
J 2
(-4400 630);
DISPLAY 0.723404 (-4400 630);
PAINT GREEN (-4400 630);
DISPLAY INVISIBLE (-4400 630);
FORCEPROP 1 LAST PART_NUMBER BEBL0172Z00
J 2
(-4175 685);
DISPLAY 0.489362 (-4175 685);
PAINT SKYBLUE (-4175 685);
DISPLAY INVISIBLE (-4175 685);
FORCEADD UNIVERSAL_GND..1
(-4750 375);
FORCEPROP 3 LASTPIN (-4750 425) SIG_NAME GND\g
J 0
(-4740 435);
DISPLAY 0.659574 (-4740 435);
PAINT MONO (-4740 435);
DISPLAY INVISIBLE (-4740 435);
FORCEPROP 2 LAST CDS_LIB pure_quanta_power
J 0
(-4750 375);
DISPLAY INVISIBLE (-4750 375);
FORCEPROP 2 LAST BOM_COST OCP3.0 
J 0
(-4950 450);
DISPLAY 0.680851 (-4950 450);
DISPLAY INVISIBLE (-4950 450);
FORCEPROP 1 LAST HDL_POWER GND
J 1
(-4725 300);
DISPLAY 0.872340 (-4725 300);
PAINT GREEN (-4725 300);
DISPLAY INVISIBLE (-4725 300);
FORCEPROP 1 LAST PATH I39
J 0
(-4675 375);
DISPLAY 0.872340 (-4675 375);
PAINT AQUA (-4675 375);
DISPLAY INVISIBLE (-4675 375);
FORCEADD UNIVERSAL_POWER..1
(-3950 5775);
FORCEPROP 3 LASTPIN (-3950 5725) SIG_NAME P3V3_AUX\g
J 0
(-3940 5735);
DISPLAY 0.659574 (-3940 5735);
PAINT MONO (-3940 5735);
DISPLAY INVISIBLE (-3940 5735);
FORCEPROP 1 LAST HDL_POWER P3V3_AUX
J 1
(-3950 5825);
DISPLAY 0.489362 (-3950 5825);
PAINT GREEN (-3950 5825);
FORCEPROP 2 LAST BOM_COST OCP3.0 
J 0
(-3950 5875);
DISPLAY 0.680851 (-3950 5875);
DISPLAY INVISIBLE (-3950 5875);
FORCEPROP 2 LAST CDS_LIB pure_quanta_power
J 0
(-3950 5775);
DISPLAY INVISIBLE (-3950 5775);
FORCEPROP 1 LAST PATH I4
J 0
(-3900 5800);
DISPLAY 0.872340 (-3900 5800);
PAINT AQUA (-3900 5800);
DISPLAY INVISIBLE (-3900 5800);
FORCEADD P1V0..1
(-2725 975);
FORCEPROP 3 LASTPIN (-2725 925) SIG_NAME P5V_AUX\g
J 0
(-2715 935);
DISPLAY 0.659574 (-2715 935);
PAINT MONO (-2715 935);
DISPLAY INVISIBLE (-2715 935);
FORCEPROP 1 LAST HDL_POWER P5V_AUX
J 1
(-2725 1025);
DISPLAY 0.489362 (-2725 1025);
PAINT GREEN (-2725 1025);
FORCEPROP 2 LAST CDS_LIB pure_quanta_power
J 0
(-2725 975);
DISPLAY INVISIBLE (-2725 975);
FORCEPROP 1 LAST PATH I40
J 0
(-2675 1000);
DISPLAY 0.872340 (-2675 1000);
PAINT AQUA (-2675 1000);
DISPLAY INVISIBLE (-2675 1000);
FORCEADD Q_RES..1
(-3275 550);
FORCEPROP 1 LAST LOCATION R1207
J 0
(-3325 600);
DISPLAY 0.489362 (-3325 600);
PAINT SKYBLUE (-3325 600);
FORCEPROP 0 LAST $SEC 1
J 0
(-3325 700);
DISPLAY 0.680851 (-3325 700);
PAINT MONO (-3325 700);
DISPLAY INVISIBLE (-3325 700);
FORCEPROP 0 LAST CDS_SEC 1
J 0
(-3325 700);
DISPLAY 0.680851 (-3325 700);
DISPLAY INVISIBLE (-3325 700);
FORCEPROP 1 LASTPIN (-3375 550) $PN 1
J 0
(-3363 562);
DISPLAY 0.489362 (-3363 562);
PAINT MONO (-3363 562);
FORCEPROP 1 LASTPIN (-3175 550) $PN 2
J 0
(-3213 562);
DISPLAY 0.489362 (-3213 562);
PAINT MONO (-3213 562);
FORCEPROP 1 LAST MATERIAL CHIP
J 0
(-3275 400);
DISPLAY 0.489362 (-3275 400);
PAINT SKYBLUE (-3275 400);
FORCEPROP 1 LAST TOLERANCE 1%
J 0
(-3275 450);
DISPLAY 0.489362 (-3275 450);
PAINT SKYBLUE (-3275 450);
FORCEPROP 1 LAST PACK_TYPE 0402LF
J 0
(-3025 400);
DISPLAY 0.489362 (-3025 400);
PAINT SKYBLUE (-3025 400);
FORCEPROP 1 LAST VALUE 470
J 2
(-3300 450);
DISPLAY 0.489362 (-3300 450);
PAINT SKYBLUE (-3300 450);
FORCEPROP 1 LAST WATTAGE 1/16W
J 2
(-3300 400);
DISPLAY 0.489362 (-3300 400);
PAINT SKYBLUE (-3300 400);
FORCEPROP 2 LAST CDS_LIB pure_quanta
J 0
(-3275 550);
DISPLAY INVISIBLE (-3275 550);
FORCEPROP 1 LAST PATH I41
J 0
(-3325 700);
DISPLAY 0.978723 (-3325 700);
PAINT WHITE (-3325 700);
DISPLAY INVISIBLE (-3325 700);
FORCEPROP 1 LAST PART_NUMBER CS14702FB04
J 0
(-3325 650);
DISPLAY 0.489362 (-3325 650);
PAINT SKYBLUE (-3325 650);
DISPLAY INVISIBLE (-3325 650);
FORCEADD Q_RES..1
(-3125 1975);
FORCEPROP 1 LAST LOCATION R1208
J 0
(-3175 2025);
DISPLAY 0.489362 (-3175 2025);
PAINT SKYBLUE (-3175 2025);
FORCEPROP 0 LAST $SEC 1
J 0
(-3175 2125);
DISPLAY 0.680851 (-3175 2125);
PAINT MONO (-3175 2125);
DISPLAY INVISIBLE (-3175 2125);
FORCEPROP 0 LAST CDS_SEC 1
J 0
(-3175 2125);
DISPLAY 0.680851 (-3175 2125);
DISPLAY INVISIBLE (-3175 2125);
FORCEPROP 1 LASTPIN (-3225 1975) $PN 1
J 0
(-3213 1987);
DISPLAY 0.489362 (-3213 1987);
PAINT MONO (-3213 1987);
FORCEPROP 1 LASTPIN (-3025 1975) $PN 2
J 0
(-3063 1987);
DISPLAY 0.489362 (-3063 1987);
PAINT MONO (-3063 1987);
FORCEPROP 1 LAST MATERIAL CHIP
J 0
(-3125 1825);
DISPLAY 0.489362 (-3125 1825);
PAINT SKYBLUE (-3125 1825);
FORCEPROP 1 LAST PACK_TYPE 0402LF
J 0
(-2875 1825);
DISPLAY 0.489362 (-2875 1825);
PAINT SKYBLUE (-2875 1825);
FORCEPROP 1 LAST TOLERANCE 1%
J 0
(-3125 1875);
DISPLAY 0.489362 (-3125 1875);
PAINT SKYBLUE (-3125 1875);
FORCEPROP 1 LAST VALUE 470
J 2
(-3150 1875);
DISPLAY 0.489362 (-3150 1875);
PAINT SKYBLUE (-3150 1875);
FORCEPROP 1 LAST WATTAGE 1/16W
J 2
(-3150 1825);
DISPLAY 0.489362 (-3150 1825);
PAINT SKYBLUE (-3150 1825);
FORCEPROP 2 LAST CDS_LIB pure_quanta
J 0
(-3125 1975);
DISPLAY INVISIBLE (-3125 1975);
FORCEPROP 1 LAST PATH I42
J 0
(-3175 2125);
DISPLAY 0.978723 (-3175 2125);
PAINT WHITE (-3175 2125);
DISPLAY INVISIBLE (-3175 2125);
FORCEPROP 1 LAST PART_NUMBER CS14702FB04
J 0
(-3175 2075);
DISPLAY 0.489362 (-3175 2075);
PAINT SKYBLUE (-3175 2075);
DISPLAY INVISIBLE (-3175 2075);
FORCEADD Q_LED..1
R 2
(-4125 1975);
FORCEPROP 1 LAST LOCATION D46
J 2
(-4025 2160);
DISPLAY 0.489362 (-4025 2160);
PAINT SKYBLUE (-4025 2160);
FORCEPROP 0 LAST $SEC 1
J 0
(-4025 2350);
DISPLAY 0.680851 (-4025 2350);
PAINT MONO (-4025 2350);
DISPLAY INVISIBLE (-4025 2350);
FORCEPROP 0 LAST CDS_SEC 1
J 0
(-4025 2350);
DISPLAY 0.680851 (-4025 2350);
DISPLAY INVISIBLE (-4025 2350);
FORCEPROP 0 LASTPIN (-3975 1975) $PN A
J 0
(-3965 1985);
DISPLAY 0.489362 (-3965 1985);
PAINT MONO (-3965 1985);
FORCEPROP 0 LASTPIN (-4275 1975) $PN C
J 2
(-4285 1985);
DISPLAY 0.489362 (-4285 1985);
PAINT MONO (-4285 1985);
FORCEPROP 2 LAST PACK_TYPE SMLF
J 2
(-4025 2200);
DISPLAY 0.489362 (-4025 2200);
PAINT SKYBLUE (-4025 2200);
FORCEPROP 2 LASTPIN (-3975 1975) SIG_NAME PU_P12V_ALL_PWROK_LED
J 0
(-4010 2010);
DISPLAY 0.489362 (-4010 2010);
FORCEPROP 2 LASTPROP $XRERR UNIQUE?
J 0
(-4250 2010);
DISPLAY 0.638298 (-4250 2010);
PAINT MONO (-4250 2010);
DISPLAY INVISIBLE (-4250 2010);
FORCEPROP 2 LAST COLOR LED_BLUE
J 2
(-4025 2300);
DISPLAY 0.489362 (-4025 2300);
FORCEPROP 1 LAST MATERIAL IC
J 2
(-4025 2055);
DISPLAY 0.489362 (-4025 2055);
PAINT SKYBLUE (-4025 2055);
FORCEPROP 2 LAST MANUF_PN LTST-C281TBKT-5A
J 2
(-4025 2250);
DISPLAY 0.680851 (-4025 2250);
FORCEPROP 1 LAST NEEDS_NO_SIZE TRUE
J 2
(-4125 1975);
DISPLAY 0.468085 (-4125 1975);
PAINT GREEN (-4125 1975);
DISPLAY INVISIBLE (-4125 1975);
FORCEPROP 2 LAST CDS_LIB pure_quanta
J 0
(-4125 1975);
DISPLAY INVISIBLE (-4125 1975);
FORCEPROP 1 LAST PATH I43
J 2
(-4250 2055);
DISPLAY 0.723404 (-4250 2055);
PAINT GREEN (-4250 2055);
DISPLAY INVISIBLE (-4250 2055);
FORCEPROP 1 LAST PART_NUMBER BEBL0172Z00
J 2
(-4025 2110);
DISPLAY 0.489362 (-4025 2110);
PAINT SKYBLUE (-4025 2110);
DISPLAY INVISIBLE (-4025 2110);
FORCEADD MOSFET_N_GSD..1
(-4875 1625);
FORCEPROP 1 LAST LOCATION Q12
J 0
(-4774 1670);
DISPLAY 0.489362 (-4774 1670);
PAINT SKYBLUE (-4774 1670);
FORCEPROP 0 LAST $SEC 1
J 0
(-4775 1850);
DISPLAY 0.680851 (-4775 1850);
PAINT MONO (-4775 1850);
DISPLAY INVISIBLE (-4775 1850);
FORCEPROP 0 LAST CDS_SEC 1
J 0
(-4775 1850);
DISPLAY 0.680851 (-4775 1850);
DISPLAY INVISIBLE (-4775 1850);
FORCEPROP 0 LASTPIN (-4850 1775) $PN D
R 1
J 0
(-4860 1785);
DISPLAY 0.489362 (-4860 1785);
PAINT MONO (-4860 1785);
FORCEPROP 0 LASTPIN (-5050 1575) $PN G
J 2
(-5060 1585);
DISPLAY 0.489362 (-5060 1585);
PAINT MONO (-5060 1585);
FORCEPROP 0 LASTPIN (-4850 1475) $PN S
R 1
J 2
(-4860 1465);
DISPLAY 0.489362 (-4860 1465);
PAINT MONO (-4860 1465);
FORCEPROP 2 LAST VALUE NX138BK
J 0
(-4775 1750);
DISPLAY 0.489362 (-4775 1750);
PAINT SKYBLUE (-4775 1750);
FORCEPROP 1 LAST MATERIAL IC
J 0
(-4774 1525);
DISPLAY 0.489362 (-4774 1525);
PAINT SKYBLUE (-4774 1525);
FORCEPROP 2 LAST PART_TYPE SMLF
J 0
(-4775 1800);
DISPLAY 1.021277 (-4775 1800);
FORCEPROP 2 LAST CDS_LIB pure_quanta
J 0
(-4875 1625);
DISPLAY INVISIBLE (-4875 1625);
FORCEPROP 1 LAST CDS_LMAN_SYM_OUTLINE -100,100,100,-100
J 0
(-4875 1625);
DISPLAY 0.468085 (-4875 1625);
PAINT GREEN (-4875 1625);
DISPLAY INVISIBLE (-4875 1625);
FORCEPROP 1 LAST NEEDS_NO_SIZE TRUE
J 0
(-4875 1625);
DISPLAY 0.468085 (-4875 1625);
PAINT GREEN (-4875 1625);
DISPLAY INVISIBLE (-4875 1625);
FORCEPROP 1 LAST PATH I44
J 0
(-4875 1625);
DISPLAY 0.723404 (-4875 1625);
PAINT GREEN (-4875 1625);
DISPLAY INVISIBLE (-4875 1625);
FORCEPROP 1 LAST PART_NUMBER BAM01380023
J 0
(-4774 1605);
DISPLAY 0.489362 (-4774 1605);
PAINT SKYBLUE (-4774 1605);
DISPLAY INVISIBLE (-4774 1605);
FORCEADD P1V0..1
(-2550 2400);
FORCEPROP 3 LASTPIN (-2550 2350) SIG_NAME P5V_AUX\g
J 0
(-2540 2360);
DISPLAY 0.659574 (-2540 2360);
PAINT MONO (-2540 2360);
DISPLAY INVISIBLE (-2540 2360);
FORCEPROP 1 LAST HDL_POWER P5V_AUX
J 1
(-2550 2450);
DISPLAY 0.489362 (-2550 2450);
PAINT GREEN (-2550 2450);
FORCEPROP 2 LAST CDS_LIB pure_quanta_power
J 0
(-2550 2400);
DISPLAY INVISIBLE (-2550 2400);
FORCEPROP 1 LAST PATH I45
J 0
(-2500 2425);
DISPLAY 0.872340 (-2500 2425);
PAINT AQUA (-2500 2425);
DISPLAY INVISIBLE (-2500 2425);
FORCEADD UNIVERSAL_GND..1
(-4850 1300);
FORCEPROP 3 LASTPIN (-4850 1350) SIG_NAME GND\g
J 0
(-4840 1360);
DISPLAY 0.659574 (-4840 1360);
PAINT MONO (-4840 1360);
DISPLAY INVISIBLE (-4840 1360);
FORCEPROP 2 LAST BOM_COST OCP3.0 
J 0
(-5050 1375);
DISPLAY 0.680851 (-5050 1375);
DISPLAY INVISIBLE (-5050 1375);
FORCEPROP 2 LAST CDS_LIB pure_quanta_power
J 0
(-4850 1300);
DISPLAY INVISIBLE (-4850 1300);
FORCEPROP 1 LAST HDL_POWER GND
J 1
(-4825 1225);
DISPLAY 0.872340 (-4825 1225);
PAINT GREEN (-4825 1225);
DISPLAY INVISIBLE (-4825 1225);
FORCEPROP 1 LAST PATH I46
J 0
(-4775 1300);
DISPLAY 0.872340 (-4775 1300);
PAINT AQUA (-4775 1300);
DISPLAY INVISIBLE (-4775 1300);
FORCEADD OFFPAGE..1
(-5875 1575);
FORCEPROP 2 LAST $XR0 81 
J 0
(-6096 1575);
DISPLAY 0.638298 (-6096 1575);
PAINT MONO (-6096 1575);
FORCEPROP 2 LAST CDS_LIB standard
J 0
(-5875 1575);
DISPLAY INVISIBLE (-5875 1575);
FORCEPROP 1 LAST OFFPAGE TRUE
J 0
(-5550 1450);
DISPLAY 0.872340 (-5550 1450);
PAINT GREEN (-5550 1450);
DISPLAY INVISIBLE (-5550 1450);
FORCEPROP 1 LAST COMMENT_BODY TRUE
J 0
(-5750 1475);
DISPLAY 0.872340 (-5750 1475);
PAINT GREEN (-5750 1475);
DISPLAY INVISIBLE (-5750 1475);
FORCEPROP 2 LAST PATH I47
J 0
(-5825 1650);
DISPLAY 0.680851 (-5825 1650);
DISPLAY INVISIBLE (-5825 1650);
FORCEADD P1V0..1
(-7200 5750);
FORCEPROP 3 LASTPIN (-7200 5700) SIG_NAME P1V8_AUX\g
J 0
(-7190 5710);
DISPLAY 0.659574 (-7190 5710);
PAINT MONO (-7190 5710);
DISPLAY INVISIBLE (-7190 5710);
FORCEPROP 1 LAST HDL_POWER P1V8_AUX
J 1
(-7200 5800);
DISPLAY 0.489362 (-7200 5800);
PAINT GREEN (-7200 5800);
FORCEPROP 2 LAST CDS_LIB pure_quanta_power
J 0
(-7200 5750);
DISPLAY INVISIBLE (-7200 5750);
FORCEPROP 1 LAST PATH I48
J 0
(-7150 5775);
DISPLAY 0.872340 (-7150 5775);
PAINT AQUA (-7150 5775);
DISPLAY INVISIBLE (-7150 5775);
FORCEADD Q_RES..2
(-3950 5425);
FORCEPROP 1 LAST LOCATION R946
J 0
(-3905 5550);
DISPLAY 0.489362 (-3905 5550);
PAINT SKYBLUE (-3905 5550);
FORCEPROP 0 LAST $SEC 1
J 0
(-3900 5600);
DISPLAY 0.680851 (-3900 5600);
PAINT MONO (-3900 5600);
DISPLAY INVISIBLE (-3900 5600);
FORCEPROP 0 LAST CDS_SEC 1
J 0
(-3900 5600);
DISPLAY 0.680851 (-3900 5600);
DISPLAY INVISIBLE (-3900 5600);
FORCEPROP 1 LASTPIN (-3950 5525) $PN 1
J 0
(-3945 5487);
DISPLAY 0.489362 (-3945 5487);
PAINT MONO (-3945 5487);
FORCEPROP 1 LASTPIN (-3950 5325) $PN 2
J 0
(-3945 5335);
DISPLAY 0.489362 (-3945 5335);
PAINT MONO (-3945 5335);
FORCEPROP 1 LAST TOLERANCE 5%
J 0
(-3905 5450);
DISPLAY 0.489362 (-3905 5450);
PAINT SKYBLUE (-3905 5450);
FORCEPROP 1 LAST VALUE 4.7K
J 0
(-3905 5500);
DISPLAY 0.489362 (-3905 5500);
PAINT SKYBLUE (-3905 5500);
FORCEPROP 1 LAST MATERIAL CHIP
J 0
(-3910 5350);
DISPLAY 0.489362 (-3910 5350);
PAINT SKYBLUE (-3910 5350);
FORCEPROP 1 LAST WATTAGE 1/16W
J 0
(-3910 5400);
DISPLAY 0.489362 (-3910 5400);
PAINT SKYBLUE (-3910 5400);
FORCEPROP 1 LAST PACK_TYPE 0402LF
J 0
(-3910 5250);
DISPLAY 0.489362 (-3910 5250);
PAINT SKYBLUE (-3910 5250);
DISPLAY INVISIBLE (-3910 5250);
FORCEPROP 2 LAST BOM_COST OCP3.0 
J 0
(-3900 5600);
DISPLAY 0.680851 (-3900 5600);
DISPLAY INVISIBLE (-3900 5600);
FORCEPROP 2 LAST CDS_LIB pure_quanta
J 0
(-3950 5425);
DISPLAY INVISIBLE (-3950 5425);
FORCEPROP 1 LAST PATH I5
J 0
(-3900 5600);
DISPLAY 0.978723 (-3900 5600);
PAINT WHITE (-3900 5600);
DISPLAY INVISIBLE (-3900 5600);
FORCEPROP 1 LAST PART_NUMBER CS24702JB10
J 0
(-3910 5300);
DISPLAY 0.489362 (-3910 5300);
PAINT SKYBLUE (-3910 5300);
DISPLAY INVISIBLE (-3910 5300);
FORCEADD GND..1
R 1
(-4000 5175);
FORCEPROP 3 LASTPIN (-4050 5175) SIG_NAME GND\g
J 0
(-4040 5185);
DISPLAY 0.659574 (-4040 5185);
PAINT MONO (-4040 5185);
DISPLAY INVISIBLE (-4040 5185);
FORCEPROP 1 LAST SIZE 1B
R 1
J 0
(-3950 5250);
DISPLAY 0.851064 (-3950 5250);
PAINT GREEN (-3950 5250);
DISPLAY INVISIBLE (-3950 5250);
FORCEPROP 2 LAST BOM_COST MEM
R 1
J 0
(-4075 5075);
DISPLAY 0.808511 (-4075 5075);
DISPLAY INVISIBLE (-4075 5075);
FORCEPROP 2 LAST CDS_LIB pure_quanta_power
J 0
(-4000 5175);
DISPLAY INVISIBLE (-4000 5175);
FORCEPROP 1 LAST HDL_POWER GND
R 1
J 0
(-4150 5175);
DISPLAY 0.851064 (-4150 5175);
PAINT GREEN (-4150 5175);
DISPLAY INVISIBLE (-4150 5175);
FORCEPROP 1 LAST PATH I6
R 1
J 0
(-4000 5250);
DISPLAY 0.872340 (-4000 5250);
PAINT AQUA (-4000 5250);
DISPLAY INVISIBLE (-4000 5250);
FORCEADD Q_RES..1
(-2000 5075);
FORCEPROP 1 LAST LOCATION R948
J 0
(-2150 5100);
DISPLAY 0.489362 (-2150 5100);
PAINT SKYBLUE (-2150 5100);
FORCEPROP 0 LAST $SEC 1
J 0
(-2150 5150);
DISPLAY 0.680851 (-2150 5150);
PAINT MONO (-2150 5150);
DISPLAY INVISIBLE (-2150 5150);
FORCEPROP 0 LAST CDS_SEC 1
J 0
(-2150 5150);
DISPLAY 0.680851 (-2150 5150);
DISPLAY INVISIBLE (-2150 5150);
FORCEPROP 1 LASTPIN (-2100 5075) $PN 1
J 0
(-2088 5087);
DISPLAY 0.489362 (-2088 5087);
PAINT MONO (-2088 5087);
FORCEPROP 1 LASTPIN (-1900 5075) $PN 2
J 0
(-1938 5087);
DISPLAY 0.489362 (-1938 5087);
PAINT MONO (-1938 5087);
FORCEPROP 1 LAST WATTAGE 1/16W
J 2
(-1925 5000);
DISPLAY 0.489362 (-1925 5000);
PAINT SKYBLUE (-1925 5000);
FORCEPROP 1 LAST MATERIAL CHIP
J 0
(-1900 5000);
DISPLAY 0.489362 (-1900 5000);
PAINT SKYBLUE (-1900 5000);
FORCEPROP 1 LAST TOLERANCE 1%
J 0
(-2125 5000);
DISPLAY 0.489362 (-2125 5000);
PAINT SKYBLUE (-2125 5000);
FORCEPROP 1 LAST PACK_TYPE 0402LF
J 0
(-1775 5000);
DISPLAY 0.489362 (-1775 5000);
PAINT SKYBLUE (-1775 5000);
FORCEPROP 1 LAST VALUE 130
J 2
(-2150 5000);
DISPLAY 0.489362 (-2150 5000);
PAINT SKYBLUE (-2150 5000);
FORCEPROP 2 LAST CDS_LIB pure_quanta
J 0
(-2000 5075);
DISPLAY INVISIBLE (-2000 5075);
FORCEPROP 1 LAST PATH I7
J 0
(-2050 5225);
DISPLAY 0.978723 (-2050 5225);
PAINT WHITE (-2050 5225);
DISPLAY INVISIBLE (-2050 5225);
FORCEPROP 1 LAST PART_NUMBER CS11302FB03
J 0
(-1975 5125);
DISPLAY 0.638298 (-1975 5125);
PAINT SKYBLUE (-1975 5125);
DISPLAY INVISIBLE (-1975 5125);
FORCEADD Q_LED..1
R 2
(-2950 5075);
FORCEPROP 1 LAST LOCATION D5
J 2
(-2850 5260);
DISPLAY 0.489362 (-2850 5260);
PAINT SKYBLUE (-2850 5260);
FORCEPROP 0 LAST $SEC 1
J 0
(-2850 5300);
DISPLAY 0.680851 (-2850 5300);
PAINT MONO (-2850 5300);
DISPLAY INVISIBLE (-2850 5300);
FORCEPROP 0 LAST CDS_SEC 1
J 0
(-2850 5300);
DISPLAY 0.680851 (-2850 5300);
DISPLAY INVISIBLE (-2850 5300);
FORCEPROP 0 LASTPIN (-2800 5075) $PN A
J 0
(-2790 5085);
DISPLAY 0.489362 (-2790 5085);
PAINT MONO (-2790 5085);
FORCEPROP 0 LASTPIN (-3100 5075) $PN C
J 2
(-3110 5085);
DISPLAY 0.489362 (-3110 5085);
PAINT MONO (-3110 5085);
FORCEPROP 1 LAST MATERIAL IC
J 2
(-2850 5155);
DISPLAY 0.489362 (-2850 5155);
PAINT SKYBLUE (-2850 5155);
FORCEPROP 2 LAST PACK_TYPE SMLF
J 2
(-2775 4975);
DISPLAY 0.489362 (-2775 4975);
PAINT SKYBLUE (-2775 4975);
FORCEPROP 2 LAST COLOR LED_BLUE
J 2
(-2775 4875);
DISPLAY 0.489362 (-2775 4875);
FORCEPROP 2 LAST MANUF_PN LTST-C281TBKT-5A
J 2
(-2775 4925);
DISPLAY 0.680851 (-2775 4925);
FORCEPROP 2 LAST CDS_LIB pure_quanta
J 2
(-2950 5075);
DISPLAY INVISIBLE (-2950 5075);
FORCEPROP 1 LAST NEEDS_NO_SIZE TRUE
J 2
(-2950 5075);
DISPLAY 0.468085 (-2950 5075);
PAINT GREEN (-2950 5075);
DISPLAY INVISIBLE (-2950 5075);
FORCEPROP 1 LAST PATH I8
J 2
(-3075 5155);
DISPLAY 0.723404 (-3075 5155);
PAINT GREEN (-3075 5155);
DISPLAY INVISIBLE (-3075 5155);
FORCEPROP 1 LAST PART_NUMBER BEBL0172Z00
J 2
(-2850 5210);
DISPLAY 0.489362 (-2850 5210);
PAINT SKYBLUE (-2850 5210);
DISPLAY INVISIBLE (-2850 5210);
FORCEADD Q_LED..1
R 2
(-3100 3450);
FORCEPROP 1 LAST LOCATION D6
J 0
(-3200 3635);
DISPLAY 0.489362 (-3200 3635);
PAINT SKYBLUE (-3200 3635);
FORCEPROP 0 LAST $SEC 1
J 0
(-3200 3800);
DISPLAY 0.680851 (-3200 3800);
PAINT MONO (-3200 3800);
DISPLAY INVISIBLE (-3200 3800);
FORCEPROP 0 LAST CDS_SEC 1
J 0
(-3000 3825);
DISPLAY 0.680851 (-3000 3825);
DISPLAY INVISIBLE (-3000 3825);
FORCEPROP 0 LASTPIN (-2950 3450) $PN A
J 0
(-2940 3460);
DISPLAY 0.489362 (-2940 3460);
PAINT MONO (-2940 3460);
FORCEPROP 0 LASTPIN (-3250 3450) $PN C
J 2
(-3260 3460);
DISPLAY 0.489362 (-3260 3460);
PAINT MONO (-3260 3460);
FORCEPROP 1 LAST MATERIAL IC
J 0
(-3200 3530);
DISPLAY 0.489362 (-3200 3530);
PAINT SKYBLUE (-3200 3530);
FORCEPROP 2 LAST PACK_TYPE SMLF
J 0
(-3200 3675);
DISPLAY 0.489362 (-3200 3675);
PAINT SKYBLUE (-3200 3675);
FORCEPROP 2 LAST COLOR LED_YELLOW
J 0
(-3200 3775);
DISPLAY 0.489362 (-3200 3775);
FORCEPROP 2 LAST MANUF_PN LTST-C190KSKT-P
J 0
(-3200 3725);
DISPLAY 0.680851 (-3200 3725);
FORCEPROP 2 LAST CDS_LIB pure_quanta
J 0
(-3100 3450);
DISPLAY INVISIBLE (-3100 3450);
FORCEPROP 1 LAST NEEDS_NO_SIZE TRUE
J 2
(-3100 3450);
DISPLAY 0.468085 (-3100 3450);
PAINT GREEN (-3100 3450);
DISPLAY INVISIBLE (-3100 3450);
FORCEPROP 1 LAST PATH I9
J 2
(-3225 3530);
DISPLAY 0.723404 (-3225 3530);
PAINT GREEN (-3225 3530);
DISPLAY INVISIBLE (-3225 3530);
FORCEPROP 1 LAST PART_NUMBER BEYL0159Z00
J 0
(-3200 3585);
DISPLAY 0.489362 (-3200 3585);
PAINT SKYBLUE (-3200 3585);
DISPLAY INVISIBLE (-3200 3585);
FORCEADD DNS..2
(-7925 4900);
PAINT RED (-7925 4900);
FORCEPROP 2 LAST CDS_LIB mstr_misc
J 0
(-7925 4900);
DISPLAY INVISIBLE (-7925 4900);
FORCEPROP 1 LAST COMMENT_BODY TRUE
R 1
J 0
(-7850 4675);
DISPLAY 0.872340 (-7850 4675);
PAINT GREEN (-7850 4675);
DISPLAY INVISIBLE (-7850 4675);
FORCEADD QUANTA_TITLE_BLOCK_C..1
(-375 -275);
FORCEPROP 0 LAST CDS_CON_LAST_MODIFIED Thu Sep 14 16:12:15 2023
J 0
(-2260 -260);
DISPLAY INVISIBLE (-2260 -260);
FORCEPROP 1 LAST CUSTOM_TXT_CDS <CON_LAST_MODIFIED>
J 0
(-2260 -260);
DISPLAY 0.978723 (-2260 -260);
FORCEPROP 2 LAST CUSTOM_TXT_CDS <XR_PAGE_TITLE>
J 0
(-8265 4975);
DISPLAY 0.638298 (-8265 4975);
PAINT PINK (-8265 4975);
DISPLAY INVISIBLE (-8265 4975);
FORCEPROP 1 LAST CUSTOM_TXT_CDS <NAME_2>
J 0
(-3550 -225);
FORCEPROP 1 LAST CUSTOM_TXT_CDS <NAME_1>
J 0
(-3550 -100);
FORCEPROP 1 LAST CUSTOM_TXT_CDS <Q_NUMBER>
J 0
(-1778 -172);
DISPLAY 1.212766 (-1778 -172);
FORCEPROP 1 LAST CUSTOM_TXT_CDS <Q_PROJ>
J 0
(-2757 -173);
DISPLAY 1.212766 (-2757 -173);
FORCEPROP 1 LAST CUSTOM_TXT_CDS <Q_REV>
J 0
(-559 -172);
DISPLAY 1.212766 (-559 -172);
FORCEPROP 1 LAST CUSTOM_TXT_CDS <CON_PAGE_NUM> OF <CON_TOTAL_PAGES>
J 0
(-821 -257);
DISPLAY 0.978723 (-821 -257);
FORCEPROP 1 LAST Q_TITLE LED (2/2)
J 0
(-9675 -225);
DISPLAY 2.446809 (-9675 -225);
PAINT GREEN (-9675 -225);
FORCEPROP 2 LAST PAGE_BORDER TRUE
J 0
(-8265 4975);
DISPLAY 0.638298 (-8265 4975);
PAINT PINK (-8265 4975);
DISPLAY INVISIBLE (-8265 4975);
FORCEPROP 1 LAST CDS_LMAN_SYM_OUTLINE -9475,6775,100,-125
J 0
(-375 -275);
DISPLAY 0.468085 (-375 -275);
PAINT GREEN (-375 -275);
DISPLAY INVISIBLE (-375 -275);
FORCEPROP 2 LAST CDS_LIB pure_quanta
J 0
(-375 -275);
DISPLAY INVISIBLE (-375 -275);
FORCEPROP 2 LAST CDS_XR_PAGE_TITLE CR-166 : @T6G_MB_LIB.T6G(SCH_1):PAGE166
J 0
(-8265 4975);
DISPLAY 0.638298 (-8265 4975);
PAINT PINK (-8265 4975);
DISPLAY INVISIBLE (-8265 4975);
FORCEPROP 1 LAST Q_DEPT BU9
J 1
(-4138 -226);
DISPLAY 1.957447 (-4138 -226);
PAINT GREEN (-4138 -226);
DISPLAY INVISIBLE (-4138 -226);
FORCEPROP 1 LAST COMMENT_BODY TRUE
J 0
(-363 -288);
DISPLAY 0.978723 (-363 -288);
PAINT GREEN (-363 -288);
DISPLAY INVISIBLE (-363 -288);
WIRE 16 -1 (-4100 3900)(-4100 4100);
WIRE 16 -1 (-4200 3550)(-4250 3550);
WIRE 16 -1 (-4700 5175)(-4725 5175);
WIRE 16 -1 (-4950 5525)(-4950 5725);
WIRE 16 -1 (-5100 3900)(-5100 4100);
WIRE 16 -1 (-4850 3550)(-4875 3550);
WIRE 16 -1 (-7200 5300)(-7200 5350);
WIRE 16 -1 (-6775 5025)(-6850 5025);
WIRE 16 -1 (-6850 5025)(-6850 4900);
WIRE 16 -1 (-7350 3675)(-7350 3725);
WIRE 16 -1 (-6925 3400)(-7000 3400);
WIRE 16 -1 (-7000 3400)(-7000 3275);
WIRE 16 -1 (-4750 550)(-4425 550);
WIRE 16 -1 (-4750 550)(-4750 425);
WIRE 16 -1 (-3950 5525)(-3950 5725);
WIRE 16 -1 (-2725 550)(-2725 925);
WIRE 16 -1 (-2725 550)(-3175 550);
WIRE 16 -1 (-2550 1975)(-2550 2350);
WIRE 16 -1 (-2550 1975)(-3025 1975);
WIRE 16 -1 (-4850 1475)(-4850 1350);
WIRE 16 -1 (-4050 5175)(-4100 5175);
WIRE 16 -1 (-7350 3975)(-7000 3975);
WIRE 16 -1 (-7350 3975)(-7350 3925);
WIRE 16 -1 (-7350 4075)(-7350 3975);
WIRE 16 -1 (-7000 3975)(-7000 3600);
WIRE 16 -1 (-7000 3600)(-6925 3600);
WIRE 16 -1 (-4850 1775)(-4850 1975);
WIRE 16 -1 (-4850 1975)(-4275 1975);
FORCEPROP 2 LAST SIG_NAME P12V_ALL_PWROK_N
J 0
(-4785 2010);
DISPLAY 0.489362 (-4785 2010);
FORCEPROP 2 LASTPROP $XRERR UNIQUE?
J 0
(-5025 2010);
DISPLAY 0.638298 (-5025 2010);
PAINT MONO (-5025 2010);
DISPLAY INVISIBLE (-5025 2010);
WIRE 16 -1 (-3975 1975)(-3225 1975);
WIRE 16 -1 (-4875 3450)(-4850 3450);
WIRE 16 -1 (-4875 3225)(-4875 3450);
WIRE 16 -1 (-4875 3225)(-4100 3225);
FORCEPROP 2 LAST SIG_NAME SMERR_LED
J 0
(-4560 3235);
DISPLAY 0.489362 (-4560 3235);
FORCEPROP 2 LASTPROP $XRERR UNIQUE?
J 0
(-4800 3235);
DISPLAY 0.638298 (-4800 3235);
PAINT MONO (-4800 3235);
DISPLAY INVISIBLE (-4800 3235);
WIRE 16 -1 (-4100 3500)(-4100 3225);
WIRE 16 -1 (-4100 3500)(-4100 3700);
WIRE 16 -1 (-4250 3500)(-4100 3500);
WIRE 16 -1 (-4250 3450)(-3250 3450);
FORCEPROP 2 LAST SIG_NAME SMERR_LED_N
J 0
(-3810 3460);
DISPLAY 0.489362 (-3810 3460);
FORCEPROP 2 LASTPROP $XRERR UNIQUE?
J 0
(-4050 3460);
DISPLAY 0.638298 (-4050 3460);
PAINT MONO (-4050 3460);
DISPLAY INVISIBLE (-4050 3460);
WIRE 16 -1 (-5050 1575)(-5825 1575);
FORCEPROP 2 LAST SIG_NAME P12V_ALL_PWROK
J 0
(-5735 1610);
DISPLAY 0.489362 (-5735 1610);
WIRE 16 -1 (-2950 3450)(-2350 3450);
FORCEPROP 2 LAST SIG_NAME PU_SMERR_LED
J 0
(-2860 3460);
DISPLAY 0.489362 (-2860 3460);
FORCEPROP 2 LASTPROP $XRERR UNIQUE?
J 0
(-3100 3460);
DISPLAY 0.638298 (-3100 3460);
PAINT MONO (-3100 3460);
DISPLAY INVISIBLE (-3100 3460);
WIRE 16 -1 (-4125 550)(-3375 550);
FORCEPROP 2 LAST SIG_NAME P5V_STBY_PWR_LED
J 0
(-4060 560);
DISPLAY 0.489362 (-4060 560);
FORCEPROP 2 LASTPROP $XRERR UNIQUE?
J 0
(-4300 560);
DISPLAY 0.638298 (-4300 560);
PAINT MONO (-4300 560);
DISPLAY INVISIBLE (-4300 560);
WIRE 16 -1 (-1875 5675)(-1875 5075);
WIRE 16 -1 (-1875 5075)(-1900 5075);
WIRE 16 -1 (-4700 5125)(-4950 5125);
WIRE 16 -1 (-4950 5125)(-4950 5325);
WIRE 16 -1 (-4950 5125)(-5575 5125);
FORCEPROP 2 LAST SIG_NAME BOOT_RDY_BUF_LED
J 0
(-5510 5135);
DISPLAY 0.489362 (-5510 5135);
FORCEPROP 2 LASTPROP $XRERR UNIQUE?
J 0
(-5750 5135);
DISPLAY 0.638298 (-5750 5135);
PAINT MONO (-5750 5135);
DISPLAY INVISIBLE (-5750 5135);
WIRE 16 -1 (-4100 5075)(-3100 5075);
FORCEPROP 2 LAST SIG_NAME BOOT_RDY_LED_N
J 0
(-3660 5085);
DISPLAY 0.489362 (-3660 5085);
FORCEPROP 2 LASTPROP $XRERR UNIQUE?
J 0
(-3900 5085);
DISPLAY 0.638298 (-3900 5085);
PAINT MONO (-3900 5085);
DISPLAY INVISIBLE (-3900 5085);
WIRE 16 -1 (-4725 5075)(-4700 5075);
WIRE 16 -1 (-4725 4850)(-4725 5075);
WIRE 16 -1 (-4725 4850)(-3950 4850);
FORCEPROP 2 LAST SIG_NAME BOOT_RDY_LED
J 0
(-4510 4860);
DISPLAY 0.489362 (-4510 4860);
FORCEPROP 2 LASTPROP $XRERR UNIQUE?
J 0
(-4750 4860);
DISPLAY 0.638298 (-4750 4860);
PAINT MONO (-4750 4860);
DISPLAY INVISIBLE (-4750 4860);
WIRE 16 -1 (-3950 5125)(-3950 4850);
WIRE 16 -1 (-3950 5125)(-3950 5325);
WIRE 16 -1 (-4100 5125)(-3950 5125);
WIRE 16 -1 (-2800 5075)(-2100 5075);
FORCEPROP 2 LAST SIG_NAME PU_BOOT_RDY_LED
J 0
(-2685 5085);
DISPLAY 0.489362 (-2685 5085);
FORCEPROP 2 LASTPROP $XRERR UNIQUE?
J 0
(-2925 5085);
DISPLAY 0.638298 (-2925 5085);
PAINT MONO (-2925 5085);
DISPLAY INVISIBLE (-2925 5085);
WIRE 16 -1 (-2125 4050)(-2125 3450);
WIRE 16 -1 (-2125 3450)(-2150 3450);
WIRE 16 -1 (-6850 5225)(-6775 5225);
WIRE 16 -1 (-6850 5600)(-6850 5225);
WIRE 16 -1 (-7200 5600)(-6850 5600);
WIRE 16 -1 (-7200 5700)(-7200 5600);
WIRE 16 -1 (-7200 5600)(-7200 5550);
WIRE 16 -1 (-8050 4875)(-8650 4875);
FORCEPROP 2 LAST SIG_NAME BOOT_RDY_H
J 0
(-8610 4885);
DISPLAY 0.489362 (-8610 4885);
WIRE 16 -1 (-7600 4875)(-7600 5125);
WIRE 16 -1 (-7600 4875)(-7850 4875);
WIRE 16 -1 (-6775 5125)(-7600 5125);
FORCEPROP 2 LAST SIG_NAME BOOT_RDY_R1_N
J 0
(-7385 5135);
DISPLAY 0.489362 (-7385 5135);
FORCEPROP 2 LASTPROP $XRERR UNIQUE?
J 0
(-7625 5135);
DISPLAY 0.638298 (-7625 5135);
PAINT MONO (-7625 5135);
DISPLAY INVISIBLE (-7625 5135);
WIRE 16 -1 (-7850 5125)(-7600 5125);
WIRE 16 -1 (-5925 3500)(-6575 3500);
FORCEPROP 2 LAST SIG_NAME FM_SMERR_BUF_LED_N
J 0
(-6385 3540);
DISPLAY 0.489362 (-6385 3540);
FORCEPROP 2 LASTPROP $XRERR UNIQUE?
J 0
(-6625 3540);
DISPLAY 0.638298 (-6625 3540);
PAINT MONO (-6625 3540);
DISPLAY INVISIBLE (-6625 3540);
WIRE 16 -1 (-4850 3500)(-5100 3500);
WIRE 16 -1 (-5100 3500)(-5100 3700);
WIRE 16 -1 (-5725 3500)(-5100 3500);
WIRE 16 -1 (-5775 5125)(-6425 5125);
FORCEPROP 2 LAST SIG_NAME BOOT_RDY_BUF_R_LED
J 0
(-6310 5150);
DISPLAY 0.489362 (-6310 5150);
FORCEPROP 2 LASTPROP $XRERR UNIQUE?
J 0
(-6550 5150);
DISPLAY 0.638298 (-6550 5150);
PAINT MONO (-6550 5150);
DISPLAY INVISIBLE (-6550 5150);
WIRE 16 -1 (-8050 5125)(-8975 5125);
FORCEPROP 2 LAST SIG_NAME FM_BIOS_POST_CMPLT_N
J 0
(-8860 5135);
DISPLAY 0.489362 (-8860 5135);
WIRE 16 -1 (-9625 4675)(-9625 4700);
WIRE 16 -1 (-6925 3500)(-8500 3500);
FORCEPROP 2 LAST SIG_NAME FM_SMERR_LED_N
J 0
(-8275 3510);
DISPLAY 0.489362 (-8275 3510);
DOT 1 (-4100 3500);
DOT 1 (-3950 5125);
DOT 1 (-4950 5125);
DOT 1 (-7350 3975);
DOT 1 (-5100 3500);
DOT 1 (-7600 5125);
DOT 1 (-7200 5600);
FORCENOTE
P5V_AUX POWER LED
(-3125 1325) 0;
DISPLAY LEFT (-3125 1325);
DISPLAY 2.000000 (-3125 1325);
FORCENOTE
P12V POWER LED
(-3050 2675) 0;
DISPLAY LEFT (-3050 2675);
DISPLAY 2.000000 (-3050 2675);
FORCENOTE
SMERR LED
(-3150 4300) 0;
DISPLAY LEFT (-3150 4300);
DISPLAY 2.000000 (-3150 4300);
FORCENOTE
BOOT-UP READY LED
(-3325 6100) 0;
DISPLAY LEFT (-3325 6100);
DISPLAY 2.000000 (-3325 6100);
QUIT
